(kicad_sch
	(version 20250114)
	(generator "eeschema")
	(generator_version "9.0")
	(paper "A3")
	(title_block
		(title "PolarFire SoM")
		(date "2025-07-22")
		(rev "1.1.4")
		(company "Antmicro Ltd")
		(comment 1 "www.antmicro.com")
	)
	(bus_alias "SMI"
		(members "MDC" "MDIO")
	)
	(text "Decoupling"
		(exclude_from_sim no)
		(at 80.01 171.45 0)
		(effects
			(font
				(size 4 4)
				(thickness 0.8)
				(bold yes)
			)
			(justify left bottom)
		)
	)
	(text "SGMII routing guidelines:\n* Traces must be routed with 100-Ω differential impedance\n* Skew matching within a pair must be less than 5 pS\n* SGMII signals must be routed on the same layer\n* Pairs must be referenced to parallel ground plane"
		(exclude_from_sim no)
		(at 167.64 64.77 0)
		(effects
			(font
				(size 1.27 1.27)
			)
			(justify left bottom)
		)
	)
	(text "REF CLK"
		(exclude_from_sim no)
		(at 299.72 60.96 0)
		(effects
			(font
				(size 4 4)
				(thickness 0.8)
				(bold yes)
			)
			(justify left bottom)
		)
	)
	(text "Place close\nto pin 24"
		(exclude_from_sim no)
		(at 134.62 224.79 0)
		(effects
			(font
				(size 1.27 1.27)
			)
			(justify left bottom)
		)
	)
	(text "Place close\nto pin 9"
		(exclude_from_sim no)
		(at 102.235 224.79 0)
		(effects
			(font
				(size 1.27 1.27)
			)
			(justify left bottom)
		)
	)
	(text "Strap functions\n\nPin name |            Function                 | Value\n------------------------------------\n RX_D0   |           PHY_ADD[1:0]              |  00\n RX_D2   |           PHY_ADD[3:2]              |  00\n RX_CTRL |       - / Autoneg Disable           |  -0\n GPIO_0  |      RGMII Clock Skew RX[0]         |  0-\n GPIO_1  |      RGMII Clock Skew RX[2:1]       |  00\n LED_2   |      RGMII Clock Skew TX[1:0]       |  00\n LED_1   | ANEG_SEL / RGMII Clock Skew TX[2] |  00\n LED_0   |    Mirror Enable / SGMII Enable     |  01"
		(exclude_from_sim no)
		(at 247.65 207.01 0)
		(effects
			(font
				(size 1.27 1.27)
			)
			(justify left bottom)
			(href "https://www.ti.com/lit/ds/symlink/dp83867is.pdf#page=39")
		)
	)
	(text "Place close\nto pin 6"
		(exclude_from_sim no)
		(at 134.62 205.74 0)
		(effects
			(font
				(size 1.27 1.27)
			)
			(justify left bottom)
		)
	)
	(text "Place close\nto pin 31"
		(exclude_from_sim no)
		(at 134.62 243.84 0)
		(effects
			(font
				(size 1.27 1.27)
			)
			(justify left bottom)
		)
	)
	(text "Place close\nto pin 19"
		(exclude_from_sim no)
		(at 67.945 205.74 0)
		(effects
			(font
				(size 1.27 1.27)
			)
			(justify left bottom)
		)
	)
	(text "Place close\nto pin 3"
		(exclude_from_sim no)
		(at 102.235 205.74 0)
		(effects
			(font
				(size 1.27 1.27)
			)
			(justify left bottom)
		)
	)
	(text "Gigabit Ethernet PHY\ntransceiver with SGMII"
		(exclude_from_sim no)
		(at 15.24 26.67 0)
		(effects
			(font
				(size 4 4)
				(thickness 0.8)
				(bold yes)
			)
			(justify left bottom)
		)
	)
	(text "Place close\nto pin 41"
		(exclude_from_sim no)
		(at 67.945 243.84 0)
		(effects
			(font
				(size 1.27 1.27)
			)
			(justify left bottom)
		)
	)
	(text "Place close\nto pin 30"
		(exclude_from_sim no)
		(at 67.945 224.79 0)
		(effects
			(font
				(size 1.27 1.27)
			)
			(justify left bottom)
		)
	)
	(text "Strap resistors"
		(exclude_from_sim no)
		(at 276.86 170.18 0)
		(effects
			(font
				(size 4 4)
				(thickness 0.8)
				(bold yes)
			)
			(justify left bottom)
		)
	)
	(text "Place close\nto pin 42"
		(exclude_from_sim no)
		(at 134.62 262.89 0)
		(effects
			(font
				(size 1.27 1.27)
			)
			(justify left bottom)
		)
	)
	(junction
		(at 105.41 213.36)
		(diameter 0)
		(color 0 0 0 0)
	)
	(junction
		(at 142.24 74.93)
		(diameter 0)
		(color 0 0 0 0)
	)
	(junction
		(at 99.06 226.06)
		(diameter 0)
		(color 0 0 0 0)
	)
	(junction
		(at 137.16 194.31)
		(diameter 0)
		(color 0 0 0 0)
	)
	(junction
		(at 99.06 207.01)
		(diameter 0)
		(color 0 0 0 0)
	)
	(junction
		(at 101.6 116.84)
		(diameter 0)
		(color 0 0 0 0)
	)
	(junction
		(at 297.18 82.55)
		(diameter 0)
		(color 0 0 0 0)
	)
	(junction
		(at 142.24 86.36)
		(diameter 0)
		(color 0 0 0 0)
	)
	(junction
		(at 72.39 213.36)
		(diameter 0)
		(color 0 0 0 0)
	)
	(junction
		(at 130.81 187.96)
		(diameter 0)
		(color 0 0 0 0)
	)
	(junction
		(at 66.04 226.06)
		(diameter 0)
		(color 0 0 0 0)
	)
	(junction
		(at 66.04 187.96)
		(diameter 0)
		(color 0 0 0 0)
	)
	(junction
		(at 72.39 251.46)
		(diameter 0)
		(color 0 0 0 0)
	)
	(junction
		(at 330.2 196.85)
		(diameter 0)
		(color 0 0 0 0)
	)
	(junction
		(at 306.07 76.2)
		(diameter 0)
		(color 0 0 0 0)
	)
	(junction
		(at 66.04 207.01)
		(diameter 0)
		(color 0 0 0 0)
	)
	(junction
		(at 72.39 194.31)
		(diameter 0)
		(color 0 0 0 0)
	)
	(junction
		(at 66.04 245.11)
		(diameter 0)
		(color 0 0 0 0)
	)
	(junction
		(at 105.41 232.41)
		(diameter 0)
		(color 0 0 0 0)
	)
	(junction
		(at 157.48 114.3)
		(diameter 0)
		(color 0 0 0 0)
	)
	(junction
		(at 99.06 187.96)
		(diameter 0)
		(color 0 0 0 0)
	)
	(junction
		(at 313.69 196.85)
		(diameter 0)
		(color 0 0 0 0)
	)
	(junction
		(at 297.18 74.93)
		(diameter 0)
		(color 0 0 0 0)
	)
	(junction
		(at 72.39 232.41)
		(diameter 0)
		(color 0 0 0 0)
	)
	(junction
		(at 142.24 83.82)
		(diameter 0)
		(color 0 0 0 0)
	)
	(junction
		(at 105.41 194.31)
		(diameter 0)
		(color 0 0 0 0)
	)
	(no_connect
		(at 138.43 124.46)
	)
	(no_connect
		(at 138.43 92.71)
	)
	(no_connect
		(at 138.43 128.27)
	)
	(no_connect
		(at 138.43 66.04)
	)
	(bus_entry
		(at 76.2 106.68)
		(size 2.54 2.54)
		(stroke
			(width 0)
			(type default)
		)
	)
	(bus_entry
		(at 83.82 57.15)
		(size 2.54 2.54)
		(stroke
			(width 0)
			(type default)
		)
	)
	(bus_entry
		(at 76.2 114.3)
		(size 2.54 2.54)
		(stroke
			(width 0)
			(type default)
		)
	)
	(bus_entry
		(at 83.82 72.39)
		(size 2.54 2.54)
		(stroke
			(width 0)
			(type default)
		)
	)
	(bus_entry
		(at 83.82 59.69)
		(size 2.54 2.54)
		(stroke
			(width 0)
			(type default)
		)
	)
	(bus_entry
		(at 223.52 78.74)
		(size -2.54 2.54)
		(stroke
			(width 0)
			(type default)
		)
	)
	(bus_entry
		(at 223.52 105.41)
		(size -2.54 2.54)
		(stroke
			(width 0)
			(type default)
		)
	)
	(bus_entry
		(at 83.82 66.04)
		(size 2.54 2.54)
		(stroke
			(width 0)
			(type default)
		)
	)
	(bus_entry
		(at 223.52 76.2)
		(size -2.54 2.54)
		(stroke
			(width 0)
			(type default)
		)
	)
	(bus_entry
		(at 83.82 76.2)
		(size 2.54 2.54)
		(stroke
			(width 0)
			(type default)
		)
	)
	(bus_entry
		(at 76.2 111.76)
		(size 2.54 2.54)
		(stroke
			(width 0)
			(type default)
		)
	)
	(bus_entry
		(at 223.52 107.95)
		(size -2.54 2.54)
		(stroke
			(width 0)
			(type default)
		)
	)
	(bus_entry
		(at 76.2 104.14)
		(size 2.54 2.54)
		(stroke
			(width 0)
			(type default)
		)
	)
	(bus_entry
		(at 83.82 69.85)
		(size 2.54 2.54)
		(stroke
			(width 0)
			(type default)
		)
	)
	(bus_entry
		(at 223.52 101.6)
		(size -2.54 2.54)
		(stroke
			(width 0)
			(type default)
		)
	)
	(bus_entry
		(at 223.52 99.06)
		(size -2.54 2.54)
		(stroke
			(width 0)
			(type default)
		)
	)
	(bus_entry
		(at 83.82 78.74)
		(size 2.54 2.54)
		(stroke
			(width 0)
			(type default)
		)
	)
	(bus_entry
		(at 83.82 63.5)
		(size 2.54 2.54)
		(stroke
			(width 0)
			(type default)
		)
	)
	(wire
		(pts
			(xy 137.16 193.04) (xy 137.16 194.31)
		)
		(stroke
			(width 0)
			(type default)
		)
	)
	(wire
		(pts
			(xy 138.43 90.17) (xy 152.4 90.17)
		)
		(stroke
			(width 0)
			(type default)
		)
	)
	(wire
		(pts
			(xy 130.81 250.19) (xy 130.81 251.46)
		)
		(stroke
			(width 0)
			(type default)
		)
	)
	(bus
		(pts
			(xy 223.52 105.41) (xy 223.52 107.95)
		)
		(stroke
			(width 0)
			(type default)
		)
	)
	(bus
		(pts
			(xy 83.82 72.39) (xy 83.82 76.2)
		)
		(stroke
			(width 0)
			(type default)
		)
	)
	(bus
		(pts
			(xy 223.52 76.2) (xy 223.52 78.74)
		)
		(stroke
			(width 0)
			(type default)
		)
	)
	(wire
		(pts
			(xy 101.6 128.27) (xy 101.6 130.81)
		)
		(stroke
			(width 0)
			(type default)
		)
	)
	(wire
		(pts
			(xy 138.43 110.49) (xy 220.98 110.49)
		)
		(stroke
			(width 0)
			(type default)
		)
	)
	(wire
		(pts
			(xy 72.39 245.11) (xy 66.04 245.11)
		)
		(stroke
			(width 0)
			(type default)
		)
	)
	(wire
		(pts
			(xy 105.41 231.14) (xy 105.41 232.41)
		)
		(stroke
			(width 0)
			(type default)
		)
	)
	(wire
		(pts
			(xy 99.06 231.14) (xy 99.06 232.41)
		)
		(stroke
			(width 0)
			(type default)
		)
	)
	(wire
		(pts
			(xy 138.43 63.5) (xy 147.32 63.5)
		)
		(stroke
			(width 0)
			(type default)
		)
	)
	(wire
		(pts
			(xy 138.43 107.95) (xy 220.98 107.95)
		)
		(stroke
			(width 0)
			(type default)
		)
	)
	(wire
		(pts
			(xy 330.2 203.2) (xy 330.2 204.47)
		)
		(stroke
			(width 0)
			(type default)
		)
	)
	(bus
		(pts
			(xy 226.06 71.12) (xy 224.79 71.12)
		)
		(stroke
			(width 0)
			(type default)
		)
	)
	(wire
		(pts
			(xy 168.91 78.74) (xy 220.98 78.74)
		)
		(stroke
			(width 0)
			(type default)
		)
	)
	(wire
		(pts
			(xy 157.48 114.3) (xy 157.48 115.57)
		)
		(stroke
			(width 0)
			(type default)
		)
	)
	(bus
		(pts
			(xy 83.82 57.15) (xy 83.82 59.69)
		)
		(stroke
			(width 0)
			(type default)
		)
	)
	(wire
		(pts
			(xy 99.06 193.04) (xy 99.06 194.31)
		)
		(stroke
			(width 0)
			(type default)
		)
	)
	(wire
		(pts
			(xy 78.74 116.84) (xy 101.6 116.84)
		)
		(stroke
			(width 0)
			(type default)
		)
	)
	(wire
		(pts
			(xy 166.37 99.06) (xy 179.07 99.06)
		)
		(stroke
			(width 0)
			(type default)
		)
	)
	(wire
		(pts
			(xy 99.06 224.79) (xy 99.06 226.06)
		)
		(stroke
			(width 0)
			(type default)
		)
	)
	(wire
		(pts
			(xy 72.39 250.19) (xy 72.39 251.46)
		)
		(stroke
			(width 0)
			(type default)
		)
	)
	(bus
		(pts
			(xy 224.79 71.12) (xy 223.52 72.39)
		)
		(stroke
			(width 0)
			(type default)
		)
	)
	(wire
		(pts
			(xy 168.91 96.52) (xy 179.07 96.52)
		)
		(stroke
			(width 0)
			(type default)
		)
	)
	(wire
		(pts
			(xy 66.04 243.84) (xy 66.04 245.11)
		)
		(stroke
			(width 0)
			(type default)
		)
	)
	(wire
		(pts
			(xy 67.31 124.46) (xy 74.93 124.46)
		)
		(stroke
			(width 0)
			(type default)
		)
	)
	(wire
		(pts
			(xy 67.31 123.19) (xy 67.31 124.46)
		)
		(stroke
			(width 0)
			(type default)
		)
	)
	(wire
		(pts
			(xy 138.43 68.58) (xy 153.67 68.58)
		)
		(stroke
			(width 0)
			(type default)
		)
	)
	(wire
		(pts
			(xy 138.43 114.3) (xy 157.48 114.3)
		)
		(stroke
			(width 0)
			(type default)
		)
	)
	(wire
		(pts
			(xy 138.43 78.74) (xy 163.83 78.74)
		)
		(stroke
			(width 0)
			(type default)
		)
	)
	(wire
		(pts
			(xy 66.04 232.41) (xy 72.39 232.41)
		)
		(stroke
			(width 0)
			(type default)
		)
	)
	(wire
		(pts
			(xy 99.06 213.36) (xy 105.41 213.36)
		)
		(stroke
			(width 0)
			(type default)
		)
	)
	(wire
		(pts
			(xy 80.01 124.46) (xy 101.6 124.46)
		)
		(stroke
			(width 0)
			(type default)
		)
	)
	(wire
		(pts
			(xy 154.94 86.36) (xy 158.75 86.36)
		)
		(stroke
			(width 0)
			(type default)
		)
	)
	(bus
		(pts
			(xy 224.79 102.87) (xy 226.06 102.87)
		)
		(stroke
			(width 0)
			(type default)
		)
	)
	(wire
		(pts
			(xy 130.81 262.89) (xy 130.81 264.16)
		)
		(stroke
			(width 0)
			(type default)
		)
	)
	(wire
		(pts
			(xy 68.58 93.98) (xy 104.14 93.98)
		)
		(stroke
			(width 0)
			(type default)
		)
	)
	(wire
		(pts
			(xy 138.43 81.28) (xy 161.29 81.28)
		)
		(stroke
			(width 0)
			(type default)
		)
	)
	(wire
		(pts
			(xy 105.41 212.09) (xy 105.41 213.36)
		)
		(stroke
			(width 0)
			(type default)
		)
	)
	(wire
		(pts
			(xy 140.97 59.69) (xy 140.97 57.15)
		)
		(stroke
			(width 0)
			(type default)
		)
	)
	(bus
		(pts
			(xy 223.52 99.06) (xy 223.52 101.6)
		)
		(stroke
			(width 0)
			(type default)
		)
	)
	(wire
		(pts
			(xy 195.58 113.03) (xy 187.96 113.03)
		)
		(stroke
			(width 0)
			(type default)
		)
	)
	(wire
		(pts
			(xy 306.07 78.74) (xy 306.07 76.2)
		)
		(stroke
			(width 0)
			(type default)
		)
	)
	(bus
		(pts
			(xy 223.52 104.14) (xy 223.52 105.41)
		)
		(stroke
			(width 0)
			(type default)
		)
	)
	(wire
		(pts
			(xy 66.04 205.74) (xy 66.04 207.01)
		)
		(stroke
			(width 0)
			(type default)
		)
	)
	(wire
		(pts
			(xy 147.32 63.5) (xy 147.32 60.96)
		)
		(stroke
			(width 0)
			(type default)
		)
	)
	(wire
		(pts
			(xy 86.36 78.74) (xy 104.14 78.74)
		)
		(stroke
			(width 0)
			(type default)
		)
	)
	(wire
		(pts
			(xy 99.06 99.06) (xy 104.14 99.06)
		)
		(stroke
			(width 0)
			(type default)
		)
	)
	(wire
		(pts
			(xy 130.81 194.31) (xy 137.16 194.31)
		)
		(stroke
			(width 0)
			(type default)
		)
	)
	(wire
		(pts
			(xy 138.43 99.06) (xy 161.29 99.06)
		)
		(stroke
			(width 0)
			(type default)
		)
	)
	(wire
		(pts
			(xy 138.43 74.93) (xy 142.24 74.93)
		)
		(stroke
			(width 0)
			(type default)
		)
	)
	(wire
		(pts
			(xy 138.43 59.69) (xy 140.97 59.69)
		)
		(stroke
			(width 0)
			(type default)
		)
	)
	(wire
		(pts
			(xy 74.93 86.36) (xy 74.93 87.63)
		)
		(stroke
			(width 0)
			(type default)
		)
	)
	(wire
		(pts
			(xy 105.41 187.96) (xy 99.06 187.96)
		)
		(stroke
			(width 0)
			(type default)
		)
	)
	(wire
		(pts
			(xy 166.37 104.14) (xy 220.98 104.14)
		)
		(stroke
			(width 0)
			(type default)
		)
	)
	(wire
		(pts
			(xy 86.36 59.69) (xy 104.14 59.69)
		)
		(stroke
			(width 0)
			(type default)
		)
	)
	(wire
		(pts
			(xy 130.81 205.74) (xy 130.81 207.01)
		)
		(stroke
			(width 0)
			(type default)
		)
	)
	(wire
		(pts
			(xy 307.34 81.28) (xy 306.07 81.28)
		)
		(stroke
			(width 0)
			(type default)
		)
	)
	(wire
		(pts
			(xy 330.2 196.85) (xy 330.2 195.58)
		)
		(stroke
			(width 0)
			(type default)
		)
	)
	(wire
		(pts
			(xy 138.43 104.14) (xy 161.29 104.14)
		)
		(stroke
			(width 0)
			(type default)
		)
	)
	(bus
		(pts
			(xy 83.82 66.04) (xy 83.82 69.85)
		)
		(stroke
			(width 0)
			(type default)
		)
	)
	(wire
		(pts
			(xy 86.36 74.93) (xy 104.14 74.93)
		)
		(stroke
			(width 0)
			(type default)
		)
	)
	(wire
		(pts
			(xy 297.18 81.28) (xy 297.18 82.55)
		)
		(stroke
			(width 0)
			(type default)
		)
	)
	(bus
		(pts
			(xy 76.2 104.14) (xy 76.2 106.68)
		)
		(stroke
			(width 0)
			(type default)
		)
	)
	(wire
		(pts
			(xy 313.69 189.23) (xy 313.69 190.5)
		)
		(stroke
			(width 0)
			(type default)
		)
	)
	(wire
		(pts
			(xy 138.43 121.92) (xy 148.59 121.92)
		)
		(stroke
			(width 0)
			(type default)
		)
	)
	(wire
		(pts
			(xy 297.18 74.93) (xy 297.18 76.2)
		)
		(stroke
			(width 0)
			(type default)
		)
	)
	(wire
		(pts
			(xy 99.06 96.52) (xy 104.14 96.52)
		)
		(stroke
			(width 0)
			(type default)
		)
	)
	(wire
		(pts
			(xy 138.43 72.39) (xy 142.24 72.39)
		)
		(stroke
			(width 0)
			(type default)
		)
	)
	(wire
		(pts
			(xy 142.24 72.39) (xy 142.24 74.93)
		)
		(stroke
			(width 0)
			(type default)
		)
	)
	(bus
		(pts
			(xy 83.82 63.5) (xy 83.82 66.04)
		)
		(stroke
			(width 0)
			(type default)
		)
	)
	(wire
		(pts
			(xy 297.18 82.55) (xy 297.18 83.82)
		)
		(stroke
			(width 0)
			(type default)
		)
	)
	(wire
		(pts
			(xy 86.36 72.39) (xy 104.14 72.39)
		)
		(stroke
			(width 0)
			(type default)
		)
	)
	(wire
		(pts
			(xy 313.69 203.2) (xy 313.69 204.47)
		)
		(stroke
			(width 0)
			(type default)
		)
	)
	(wire
		(pts
			(xy 138.43 96.52) (xy 163.83 96.52)
		)
		(stroke
			(width 0)
			(type default)
		)
	)
	(wire
		(pts
			(xy 78.74 109.22) (xy 104.14 109.22)
		)
		(stroke
			(width 0)
			(type default)
		)
	)
	(wire
		(pts
			(xy 153.67 66.04) (xy 153.67 68.58)
		)
		(stroke
			(width 0)
			(type default)
		)
	)
	(wire
		(pts
			(xy 66.04 250.19) (xy 66.04 251.46)
		)
		(stroke
			(width 0)
			(type default)
		)
	)
	(wire
		(pts
			(xy 306.07 76.2) (xy 307.34 76.2)
		)
		(stroke
			(width 0)
			(type default)
		)
	)
	(wire
		(pts
			(xy 86.36 68.58) (xy 104.14 68.58)
		)
		(stroke
			(width 0)
			(type default)
		)
	)
	(wire
		(pts
			(xy 330.2 196.85) (xy 349.25 196.85)
		)
		(stroke
			(width 0)
			(type default)
		)
	)
	(wire
		(pts
			(xy 168.91 101.6) (xy 220.98 101.6)
		)
		(stroke
			(width 0)
			(type default)
		)
	)
	(wire
		(pts
			(xy 307.34 78.74) (xy 306.07 78.74)
		)
		(stroke
			(width 0)
			(type default)
		)
	)
	(wire
		(pts
			(xy 105.41 193.04) (xy 105.41 194.31)
		)
		(stroke
			(width 0)
			(type default)
		)
	)
	(wire
		(pts
			(xy 99.06 212.09) (xy 99.06 213.36)
		)
		(stroke
			(width 0)
			(type default)
		)
	)
	(wire
		(pts
			(xy 142.24 86.36) (xy 149.86 86.36)
		)
		(stroke
			(width 0)
			(type default)
		)
	)
	(wire
		(pts
			(xy 66.04 212.09) (xy 66.04 213.36)
		)
		(stroke
			(width 0)
			(type default)
		)
	)
	(wire
		(pts
			(xy 99.06 205.74) (xy 99.06 207.01)
		)
		(stroke
			(width 0)
			(type default)
		)
	)
	(wire
		(pts
			(xy 99.06 86.36) (xy 104.14 86.36)
		)
		(stroke
			(width 0)
			(type default)
		)
	)
	(wire
		(pts
			(xy 306.07 81.28) (xy 306.07 82.55)
		)
		(stroke
			(width 0)
			(type default)
		)
	)
	(wire
		(pts
			(xy 66.04 213.36) (xy 72.39 213.36)
		)
		(stroke
			(width 0)
			(type default)
		)
	)
	(wire
		(pts
			(xy 86.36 81.28) (xy 104.14 81.28)
		)
		(stroke
			(width 0)
			(type default)
		)
	)
	(wire
		(pts
			(xy 138.43 118.11) (xy 160.02 118.11)
		)
		(stroke
			(width 0)
			(type default)
		)
	)
	(bus
		(pts
			(xy 82.55 54.61) (xy 81.28 54.61)
		)
		(stroke
			(width 0)
			(type default)
		)
	)
	(wire
		(pts
			(xy 130.81 243.84) (xy 130.81 245.11)
		)
		(stroke
			(width 0)
			(type default)
		)
	)
	(wire
		(pts
			(xy 66.04 224.79) (xy 66.04 226.06)
		)
		(stroke
			(width 0)
			(type default)
		)
	)
	(wire
		(pts
			(xy 78.74 114.3) (xy 104.14 114.3)
		)
		(stroke
			(width 0)
			(type default)
		)
	)
	(wire
		(pts
			(xy 130.81 224.79) (xy 130.81 226.06)
		)
		(stroke
			(width 0)
			(type default)
		)
	)
	(wire
		(pts
			(xy 101.6 116.84) (xy 101.6 124.46)
		)
		(stroke
			(width 0)
			(type default)
		)
	)
	(wire
		(pts
			(xy 72.39 231.14) (xy 72.39 232.41)
		)
		(stroke
			(width 0)
			(type default)
		)
	)
	(wire
		(pts
			(xy 86.36 62.23) (xy 104.14 62.23)
		)
		(stroke
			(width 0)
			(type default)
		)
	)
	(wire
		(pts
			(xy 130.81 231.14) (xy 130.81 232.41)
		)
		(stroke
			(width 0)
			(type default)
		)
	)
	(wire
		(pts
			(xy 104.14 128.27) (xy 101.6 128.27)
		)
		(stroke
			(width 0)
			(type default)
		)
	)
	(bus
		(pts
			(xy 224.79 102.87) (xy 223.52 104.14)
		)
		(stroke
			(width 0)
			(type default)
		)
	)
	(wire
		(pts
			(xy 99.06 194.31) (xy 105.41 194.31)
		)
		(stroke
			(width 0)
			(type default)
		)
	)
	(bus
		(pts
			(xy 74.93 109.22) (xy 76.2 110.49)
		)
		(stroke
			(width 0)
			(type default)
		)
	)
	(wire
		(pts
			(xy 66.04 251.46) (xy 72.39 251.46)
		)
		(stroke
			(width 0)
			(type default)
		)
	)
	(wire
		(pts
			(xy 99.06 232.41) (xy 105.41 232.41)
		)
		(stroke
			(width 0)
			(type default)
		)
	)
	(bus
		(pts
			(xy 76.2 111.76) (xy 76.2 114.3)
		)
		(stroke
			(width 0)
			(type default)
		)
	)
	(wire
		(pts
			(xy 130.81 269.24) (xy 130.81 270.51)
		)
		(stroke
			(width 0)
			(type default)
		)
	)
	(wire
		(pts
			(xy 330.2 189.23) (xy 330.2 190.5)
		)
		(stroke
			(width 0)
			(type default)
		)
	)
	(wire
		(pts
			(xy 157.48 113.03) (xy 157.48 114.3)
		)
		(stroke
			(width 0)
			(type default)
		)
	)
	(wire
		(pts
			(xy 66.04 187.96) (xy 72.39 187.96)
		)
		(stroke
			(width 0)
			(type default)
		)
	)
	(wire
		(pts
			(xy 66.04 207.01) (xy 72.39 207.01)
		)
		(stroke
			(width 0)
			(type default)
		)
	)
	(wire
		(pts
			(xy 58.42 93.98) (xy 63.5 93.98)
		)
		(stroke
			(width 0)
			(type default)
		)
	)
	(wire
		(pts
			(xy 66.04 193.04) (xy 66.04 194.31)
		)
		(stroke
			(width 0)
			(type default)
		)
	)
	(bus
		(pts
			(xy 82.55 54.61) (xy 83.82 55.88)
		)
		(stroke
			(width 0)
			(type default)
		)
	)
	(wire
		(pts
			(xy 330.2 196.85) (xy 330.2 198.12)
		)
		(stroke
			(width 0)
			(type default)
		)
	)
	(wire
		(pts
			(xy 66.04 186.69) (xy 66.04 187.96)
		)
		(stroke
			(width 0)
			(type default)
		)
	)
	(bus
		(pts
			(xy 83.82 76.2) (xy 83.82 78.74)
		)
		(stroke
			(width 0)
			(type default)
		)
	)
	(bus
		(pts
			(xy 76.2 110.49) (xy 76.2 111.76)
		)
		(stroke
			(width 0)
			(type default)
		)
	)
	(wire
		(pts
			(xy 101.6 116.84) (xy 104.14 116.84)
		)
		(stroke
			(width 0)
			(type default)
		)
	)
	(bus
		(pts
			(xy 76.2 102.87) (xy 76.2 104.14)
		)
		(stroke
			(width 0)
			(type default)
		)
	)
	(wire
		(pts
			(xy 138.43 86.36) (xy 142.24 86.36)
		)
		(stroke
			(width 0)
			(type default)
		)
	)
	(wire
		(pts
			(xy 138.43 83.82) (xy 142.24 83.82)
		)
		(stroke
			(width 0)
			(type default)
		)
	)
	(wire
		(pts
			(xy 99.06 186.69) (xy 99.06 187.96)
		)
		(stroke
			(width 0)
			(type default)
		)
	)
	(wire
		(pts
			(xy 130.81 212.09) (xy 130.81 213.36)
		)
		(stroke
			(width 0)
			(type default)
		)
	)
	(wire
		(pts
			(xy 130.81 187.96) (xy 137.16 187.96)
		)
		(stroke
			(width 0)
			(type default)
		)
	)
	(wire
		(pts
			(xy 66.04 231.14) (xy 66.04 232.41)
		)
		(stroke
			(width 0)
			(type default)
		)
	)
	(wire
		(pts
			(xy 166.37 81.28) (xy 220.98 81.28)
		)
		(stroke
			(width 0)
			(type default)
		)
	)
	(wire
		(pts
			(xy 105.41 226.06) (xy 99.06 226.06)
		)
		(stroke
			(width 0)
			(type default)
		)
	)
	(wire
		(pts
			(xy 142.24 83.82) (xy 142.24 86.36)
		)
		(stroke
			(width 0)
			(type default)
		)
	)
	(wire
		(pts
			(xy 138.43 101.6) (xy 163.83 101.6)
		)
		(stroke
			(width 0)
			(type default)
		)
	)
	(wire
		(pts
			(xy 313.69 196.85) (xy 313.69 198.12)
		)
		(stroke
			(width 0)
			(type default)
		)
	)
	(wire
		(pts
			(xy 72.39 212.09) (xy 72.39 213.36)
		)
		(stroke
			(width 0)
			(type default)
		)
	)
	(bus
		(pts
			(xy 83.82 69.85) (xy 83.82 72.39)
		)
		(stroke
			(width 0)
			(type default)
		)
	)
	(bus
		(pts
			(xy 74.93 101.6) (xy 76.2 102.87)
		)
		(stroke
			(width 0)
			(type default)
		)
	)
	(wire
		(pts
			(xy 130.81 186.69) (xy 130.81 187.96)
		)
		(stroke
			(width 0)
			(type default)
		)
	)
	(bus
		(pts
			(xy 83.82 55.88) (xy 83.82 57.15)
		)
		(stroke
			(width 0)
			(type default)
		)
	)
	(bus
		(pts
			(xy 223.52 72.39) (xy 223.52 76.2)
		)
		(stroke
			(width 0)
			(type default)
		)
	)
	(wire
		(pts
			(xy 326.39 76.2) (xy 335.28 76.2)
		)
		(stroke
			(width 0)
			(type default)
		)
	)
	(bus
		(pts
			(xy 223.52 78.74) (xy 223.52 99.06)
		)
		(stroke
			(width 0)
			(type default)
		)
	)
	(wire
		(pts
			(xy 142.24 74.93) (xy 142.24 83.82)
		)
		(stroke
			(width 0)
			(type default)
		)
	)
	(wire
		(pts
			(xy 297.18 74.93) (xy 306.07 74.93)
		)
		(stroke
			(width 0)
			(type default)
		)
	)
	(wire
		(pts
			(xy 66.04 194.31) (xy 72.39 194.31)
		)
		(stroke
			(width 0)
			(type default)
		)
	)
	(wire
		(pts
			(xy 66.04 226.06) (xy 72.39 226.06)
		)
		(stroke
			(width 0)
			(type default)
		)
	)
	(wire
		(pts
			(xy 297.18 73.66) (xy 297.18 74.93)
		)
		(stroke
			(width 0)
			(type default)
		)
	)
	(bus
		(pts
			(xy 74.93 101.6) (xy 73.66 101.6)
		)
		(stroke
			(width 0)
			(type default)
		)
	)
	(wire
		(pts
			(xy 157.48 115.57) (xy 160.02 115.57)
		)
		(stroke
			(width 0)
			(type default)
		)
	)
	(wire
		(pts
			(xy 306.07 74.93) (xy 306.07 76.2)
		)
		(stroke
			(width 0)
			(type default)
		)
	)
	(wire
		(pts
			(xy 326.39 196.85) (xy 313.69 196.85)
		)
		(stroke
			(width 0)
			(type default)
		)
	)
	(wire
		(pts
			(xy 78.74 106.68) (xy 104.14 106.68)
		)
		(stroke
			(width 0)
			(type default)
		)
	)
	(wire
		(pts
			(xy 157.48 113.03) (xy 182.88 113.03)
		)
		(stroke
			(width 0)
			(type default)
		)
	)
	(wire
		(pts
			(xy 99.06 91.44) (xy 104.14 91.44)
		)
		(stroke
			(width 0)
			(type default)
		)
	)
	(wire
		(pts
			(xy 74.93 86.36) (xy 93.98 86.36)
		)
		(stroke
			(width 0)
			(type default)
		)
	)
	(wire
		(pts
			(xy 313.69 195.58) (xy 313.69 196.85)
		)
		(stroke
			(width 0)
			(type default)
		)
	)
	(bus
		(pts
			(xy 74.93 109.22) (xy 73.66 109.22)
		)
		(stroke
			(width 0)
			(type default)
		)
	)
	(wire
		(pts
			(xy 130.81 193.04) (xy 130.81 194.31)
		)
		(stroke
			(width 0)
			(type default)
		)
	)
	(bus
		(pts
			(xy 83.82 59.69) (xy 83.82 63.5)
		)
		(stroke
			(width 0)
			(type default)
		)
	)
	(wire
		(pts
			(xy 93.98 104.14) (xy 104.14 104.14)
		)
		(stroke
			(width 0)
			(type default)
		)
	)
	(wire
		(pts
			(xy 99.06 207.01) (xy 105.41 207.01)
		)
		(stroke
			(width 0)
			(type default)
		)
	)
	(wire
		(pts
			(xy 86.36 66.04) (xy 104.14 66.04)
		)
		(stroke
			(width 0)
			(type default)
		)
	)
	(wire
		(pts
			(xy 72.39 193.04) (xy 72.39 194.31)
		)
		(stroke
			(width 0)
			(type default)
		)
	)
	(wire
		(pts
			(xy 297.18 82.55) (xy 306.07 82.55)
		)
		(stroke
			(width 0)
			(type default)
		)
	)
	(wire
		(pts
			(xy 158.75 86.36) (xy 158.75 88.9)
		)
		(stroke
			(width 0)
			(type default)
		)
	)
	(label "ETH.SYNC_OUT"
		(at 177.8 110.49 180)
		(effects
			(font
				(size 1.27 1.27)
			)
			(justify right bottom)
		)
	)
	(label "ETH.TXRX_B_N"
		(at 99.695 68.58 180)
		(effects
			(font
				(size 1.27 1.27)
			)
			(justify right bottom)
		)
	)
	(label "SGMII.TX0_P"
		(at 220.98 81.28 180)
		(effects
			(font
				(size 1.27 1.27)
			)
			(justify right bottom)
		)
	)
	(label "SGMII.RX0_P"
		(at 220.98 101.6 180)
		(effects
			(font
				(size 1.27 1.27)
			)
			(justify right bottom)
		)
	)
	(label "ETH.TXRX_C_P"
		(at 99.695 72.39 180)
		(effects
			(font
				(size 1.27 1.27)
			)
			(justify right bottom)
		)
	)
	(label "SGMII_SO_P"
		(at 143.51 101.6 0)
		(effects
			(font
				(size 1.27 1.27)
			)
			(justify left bottom)
		)
	)
	(label "X_I"
		(at 148.59 121.92 180)
		(effects
			(font
				(size 1.27 1.27)
			)
			(justify right bottom)
		)
	)
	(label "SGMII_CO_P"
		(at 143.51 96.52 0)
		(effects
			(font
				(size 1.27 1.27)
			)
			(justify left bottom)
		)
	)
	(label "ETH_RXCTRL"
		(at 152.4 90.17 180)
		(effects
			(font
				(size 1.27 1.27)
			)
			(justify right bottom)
		)
	)
	(label "ETH.TXRX_C_N"
		(at 99.695 74.93 180)
		(effects
			(font
				(size 1.27 1.27)
			)
			(justify right bottom)
		)
	)
	(label "ETH.TXRX_A_P"
		(at 99.695 59.69 180)
		(effects
			(font
				(size 1.27 1.27)
			)
			(justify right bottom)
		)
	)
	(label "SGMII_SI_N"
		(at 144.78 78.74 0)
		(effects
			(font
				(size 1.27 1.27)
			)
			(justify left bottom)
		)
	)
	(label "SGMII.RX0_N"
		(at 220.98 104.14 180)
		(effects
			(font
				(size 1.27 1.27)
			)
			(justify right bottom)
		)
	)
	(label "ETH.TXRX_A_N"
		(at 99.695 62.23 180)
		(effects
			(font
				(size 1.27 1.27)
			)
			(justify right bottom)
		)
	)
	(label "ETH_RXCTRL"
		(at 349.25 196.85 180)
		(effects
			(font
				(size 1.27 1.27)
			)
			(justify right bottom)
		)
	)
	(label "ETH.MDIO"
		(at 78.74 116.84 0)
		(effects
			(font
				(size 1.27 1.27)
			)
			(justify left bottom)
		)
	)
	(label "ETH.TXRX_D_P"
		(at 86.36 78.74 0)
		(effects
			(font
				(size 1.27 1.27)
			)
			(justify left bottom)
		)
	)
	(label "LED0"
		(at 93.98 104.14 0)
		(effects
			(font
				(size 1.27 1.27)
			)
			(justify left bottom)
		)
	)
	(label "SGMII_SO_N"
		(at 143.51 104.14 0)
		(effects
			(font
				(size 1.27 1.27)
			)
			(justify left bottom)
		)
	)
	(label "ETH.LED1"
		(at 78.74 106.68 0)
		(effects
			(font
				(size 1.27 1.27)
			)
			(justify left bottom)
		)
	)
	(label "ETH.TXRX_B_P"
		(at 99.695 66.04 180)
		(effects
			(font
				(size 1.27 1.27)
			)
			(justify right bottom)
		)
	)
	(label "SGMII_SI_P"
		(at 144.78 81.28 0)
		(effects
			(font
				(size 1.27 1.27)
			)
			(justify left bottom)
		)
	)
	(label "X_I"
		(at 335.28 76.2 180)
		(effects
			(font
				(size 1.27 1.27)
			)
			(justify right bottom)
		)
	)
	(label "ETH.SYNC_IN"
		(at 177.8 107.95 180)
		(effects
			(font
				(size 1.27 1.27)
			)
			(justify right bottom)
		)
	)
	(label "SGMII.TX0_N"
		(at 220.98 78.74 180)
		(effects
			(font
				(size 1.27 1.27)
			)
			(justify right bottom)
		)
	)
	(label "SGMII_CO_N"
		(at 143.51 99.06 0)
		(effects
			(font
				(size 1.27 1.27)
			)
			(justify left bottom)
		)
	)
	(label "ETH.LED2"
		(at 78.74 109.22 0)
		(effects
			(font
				(size 1.27 1.27)
			)
			(justify left bottom)
		)
	)
	(label "LED0"
		(at 326.39 196.85 180)
		(effects
			(font
				(size 1.27 1.27)
			)
			(justify right bottom)
		)
	)
	(label "ETH.TXRX_D_N"
		(at 86.36 81.28 0)
		(effects
			(font
				(size 1.27 1.27)
			)
			(justify left bottom)
		)
	)
	(label "ETH.MDC"
		(at 78.74 114.3 0)
		(effects
			(font
				(size 1.27 1.27)
			)
			(justify left bottom)
		)
	)
	(global_label "ETH_PWDN_n"
		(shape input)
		(at 160.02 115.57 0)
		(fields_autoplaced yes)
		(effects
			(font
				(size 1.27 1.27)
			)
			(justify left)
		)
		(property "Intersheetrefs" "${INTERSHEET_REFS}"
			(at 174.2864 115.4906 0)
			(effects
				(font
					(size 1.27 1.27)
				)
				(justify left)
			)
		)
	)
	(global_label "JTAG_TMS"
		(shape input)
		(at 99.06 99.06 180)
		(fields_autoplaced yes)
		(effects
			(font
				(size 1.27 1.27)
			)
			(justify right)
		)
		(property "Intersheetrefs" "${INTERSHEET_REFS}"
			(at 87.7569 98.9806 0)
			(effects
				(font
					(size 1.27 1.27)
				)
				(justify right)
			)
		)
	)
	(global_label "ETH_RESET_n"
		(shape input)
		(at 160.02 118.11 0)
		(fields_autoplaced yes)
		(effects
			(font
				(size 1.27 1.27)
			)
			(justify left)
		)
		(property "Intersheetrefs" "${INTERSHEET_REFS}"
			(at 174.7098 118.0306 0)
			(effects
				(font
					(size 1.27 1.27)
				)
				(justify left)
			)
		)
	)
	(global_label "WL_BT_TDO"
		(shape input)
		(at 99.06 91.44 180)
		(fields_autoplaced yes)
		(effects
			(font
				(size 1.27 1.27)
			)
			(justify right)
		)
		(property "Intersheetrefs" "${INTERSHEET_REFS}"
			(at 85.8544 91.44 0)
			(effects
				(font
					(size 1.27 1.27)
				)
				(justify right)
			)
		)
	)
	(global_label "MSS_REFCLK_P"
		(shape input)
		(at 179.07 96.52 0)
		(fields_autoplaced yes)
		(effects
			(font
				(size 1.27 1.27)
			)
			(justify left)
		)
		(property "Intersheetrefs" "${INTERSHEET_REFS}"
			(at 196.2065 96.52 0)
			(effects
				(font
					(size 1.27 1.27)
				)
				(justify left)
			)
		)
	)
	(global_label "MSS_REFCLK_N"
		(shape input)
		(at 179.07 99.06 0)
		(fields_autoplaced yes)
		(effects
			(font
				(size 1.27 1.27)
			)
			(justify left)
		)
		(property "Intersheetrefs" "${INTERSHEET_REFS}"
			(at 196.267 99.06 0)
			(effects
				(font
					(size 1.27 1.27)
				)
				(justify left)
			)
		)
	)
	(global_label "JTAG_TCK"
		(shape input)
		(at 99.06 96.52 180)
		(fields_autoplaced yes)
		(effects
			(font
				(size 1.27 1.27)
			)
			(justify right)
		)
		(property "Intersheetrefs" "${INTERSHEET_REFS}"
			(at 87.8779 96.4406 0)
			(effects
				(font
					(size 1.27 1.27)
				)
				(justify right)
			)
		)
	)
	(global_label "JTAG_TDO"
		(shape output)
		(at 58.42 93.98 180)
		(fields_autoplaced yes)
		(effects
			(font
				(size 1.27 1.27)
			)
			(justify right)
		)
		(property "Intersheetrefs" "${INTERSHEET_REFS}"
			(at 47.1774 93.9006 0)
			(effects
				(font
					(size 1.27 1.27)
				)
				(justify right)
			)
		)
	)
	(hierarchical_label "ETH{MDI}"
		(shape input)
		(at 81.28 54.61 180)
		(effects
			(font
				(size 1.27 1.27)
			)
			(justify right)
		)
	)
	(hierarchical_label "ETH{MDI}"
		(shape input)
		(at 226.06 102.87 0)
		(effects
			(font
				(size 1.27 1.27)
			)
			(justify left)
		)
	)
	(hierarchical_label "SGMII{SGMII}"
		(shape input)
		(at 226.06 71.12 0)
		(effects
			(font
				(size 1.27 1.27)
			)
			(justify left)
		)
	)
	(hierarchical_label "ETH{MDI}"
		(shape input)
		(at 73.66 101.6 180)
		(effects
			(font
				(size 1.27 1.27)
			)
			(justify right)
		)
	)
	(hierarchical_label "ETH{SMI}"
		(shape input)
		(at 73.66 109.22 180)
		(effects
			(font
				(size 1.27 1.27)
			)
			(justify right)
		)
	)
	(symbol
		(lib_id "antmicropower:+1V05")
		(at 130.81 205.74 0)
		(unit 1)
		(exclude_from_sim no)
		(in_bom yes)
		(on_board yes)
		(dnp no)
		(property "Reference" "#PWR0235"
			(at 130.81 209.55 0)
			(effects
				(font
					(size 1.27 1.27)
				)
				(hide yes)
			)
		)
		(property "Value" "+1V05"
			(at 130.81 201.93 0)
			(effects
				(font
					(size 1.27 1.27)
				)
			)
		)
		(property "Footprint" ""
			(at 130.81 205.74 0)
			(effects
				(font
					(size 1.27 1.27)
				)
				(hide yes)
			)
		)
		(property "Datasheet" ""
			(at 130.81 205.74 0)
			(effects
				(font
					(size 1.27 1.27)
				)
				(hide yes)
			)
		)
		(property "Description" ""
			(at 130.81 205.74 0)
			(effects
				(font
					(size 1.27 1.27)
				)
				(hide yes)
			)
		)
		(pin "1"
		)
		(instances
			(project "polarfire-som"
				(path ""
					(reference "#PWR0235")
					(unit 1)
				)
			)
		)
	)
	(symbol
		(lib_id "antmicropower:+3V3")
		(at 330.2 189.23 0)
		(unit 1)
		(exclude_from_sim no)
		(in_bom yes)
		(on_board yes)
		(dnp no)
		(fields_autoplaced yes)
		(property "Reference" "#PWR0255"
			(at 345.44 191.77 0)
			(effects
				(font
					(size 1.27 1.27)
					(thickness 0.15)
				)
				(justify left bottom)
				(hide yes)
			)
		)
		(property "Value" "+3V3"
			(at 330.2 184.15 0)
			(effects
				(font
					(size 1.27 1.27)
					(thickness 0.15)
				)
			)
		)
		(property "Footprint" ""
			(at 345.44 196.85 0)
			(effects
				(font
					(size 1.27 1.27)
					(thickness 0.15)
				)
				(justify left bottom)
				(hide yes)
			)
		)
		(property "Datasheet" ""
			(at 345.44 199.39 0)
			(effects
				(font
					(size 1.27 1.27)
					(thickness 0.15)
				)
				(justify left bottom)
				(hide yes)
			)
		)
		(property "Description" ""
			(at 330.2 189.23 0)
			(effects
				(font
					(size 1.27 1.27)
				)
				(hide yes)
			)
		)
		(property "Author" "Antmicro"
			(at 345.44 196.85 0)
			(effects
				(font
					(size 1.27 1.27)
					(thickness 0.15)
				)
				(justify left bottom)
				(hide yes)
			)
		)
		(property "License" "Apache-2.0"
			(at 345.44 199.39 0)
			(effects
				(font
					(size 1.27 1.27)
					(thickness 0.15)
				)
				(justify left bottom)
				(hide yes)
			)
		)
		(pin "1"
		)
		(instances
			(project "polarfire-som"
				(path ""
					(reference "#PWR0255")
					(unit 1)
				)
			)
		)
	)
	(symbol
		(lib_id "antmicropower:+3V3")
		(at 66.04 205.74 0)
		(unit 1)
		(exclude_from_sim no)
		(in_bom yes)
		(on_board yes)
		(dnp no)
		(fields_autoplaced yes)
		(property "Reference" "#PWR0297"
			(at 81.28 208.28 0)
			(effects
				(font
					(size 1.27 1.27)
					(thickness 0.15)
				)
				(justify left bottom)
				(hide yes)
			)
		)
		(property "Value" "+3V3"
			(at 66.04 200.66 0)
			(effects
				(font
					(size 1.27 1.27)
					(thickness 0.15)
				)
			)
		)
		(property "Footprint" ""
			(at 81.28 213.36 0)
			(effects
				(font
					(size 1.27 1.27)
					(thickness 0.15)
				)
				(justify left bottom)
				(hide yes)
			)
		)
		(property "Datasheet" ""
			(at 81.28 215.9 0)
			(effects
				(font
					(size 1.27 1.27)
					(thickness 0.15)
				)
				(justify left bottom)
				(hide yes)
			)
		)
		(property "Description" ""
			(at 66.04 205.74 0)
			(effects
				(font
					(size 1.27 1.27)
				)
				(hide yes)
			)
		)
		(property "Author" "Antmicro"
			(at 81.28 213.36 0)
			(effects
				(font
					(size 1.27 1.27)
					(thickness 0.15)
				)
				(justify left bottom)
				(hide yes)
			)
		)
		(property "License" "Apache-2.0"
			(at 81.28 215.9 0)
			(effects
				(font
					(size 1.27 1.27)
					(thickness 0.15)
				)
				(justify left bottom)
				(hide yes)
			)
		)
		(pin "1"
		)
		(instances
			(project "polarfire-som"
				(path ""
					(reference "#PWR0297")
					(unit 1)
				)
			)
		)
	)
	(symbol
		(lib_id "antmicroResistors0402:R_4k7_0402")
		(at 149.86 86.36 0)
		(unit 1)
		(exclude_from_sim no)
		(in_bom yes)
		(on_board yes)
		(dnp no)
		(property "Reference" "R92"
			(at 148.59 85.09 0)
			(effects
				(font
					(size 1.27 1.27)
					(thickness 0.15)
				)
			)
		)
		(property "Value" "R_4k7_0402"
			(at 170.18 99.06 0)
			(effects
				(font
					(size 1.27 1.27)
					(thickness 0.15)
				)
				(justify left bottom)
				(hide yes)
			)
		)
		(property "Footprint" "antmicro-footprints:R_0402_1005Metric"
			(at 170.18 101.6 0)
			(effects
				(font
					(size 1.27 1.27)
					(thickness 0.15)
				)
				(justify left bottom)
				(hide yes)
			)
		)
		(property "Datasheet" "https://www.bourns.com/docs/product-datasheets/cr.pdf"
			(at 170.18 104.14 0)
			(effects
				(font
					(size 1.27 1.27)
					(thickness 0.15)
				)
				(justify left bottom)
				(hide yes)
			)
		)
		(property "Description" "SMD Chip Resistor, 4.7 kohm, ± 1%, 62.5 mW, 0402 [1005 Metric], Thick Film, General Purpose"
			(at 149.86 86.36 0)
			(effects
				(font
					(size 1.27 1.27)
				)
				(hide yes)
			)
		)
		(property "MPN" "CR0402-FX-4701GLF"
			(at 170.18 106.68 0)
			(effects
				(font
					(size 1.27 1.27)
					(thickness 0.15)
				)
				(justify left bottom)
				(hide yes)
			)
		)
		(property "Manufacturer" "Bourns"
			(at 170.18 109.22 0)
			(effects
				(font
					(size 1.27 1.27)
					(thickness 0.15)
				)
				(justify left bottom)
				(hide yes)
			)
		)
		(property "License" "Apache-2.0"
			(at 170.18 111.76 0)
			(effects
				(font
					(size 1.27 1.27)
					(thickness 0.15)
				)
				(justify left bottom)
				(hide yes)
			)
		)
		(property "Author" "Antmicro"
			(at 170.18 114.3 0)
			(effects
				(font
					(size 1.27 1.27)
					(thickness 0.15)
				)
				(justify left bottom)
				(hide yes)
			)
		)
		(property "Val" "4k7"
			(at 156.21 85.09 0)
			(effects
				(font
					(size 1.27 1.27)
					(thickness 0.15)
				)
			)
		)
		(property "Tolerance" "1%"
			(at 170.18 96.52 0)
			(effects
				(font
					(size 1.27 1.27)
				)
				(justify left bottom)
				(hide yes)
			)
		)
		(property "Public" ""
			(at 170.18 116.84 0)
			(effects
				(font
					(size 1.27 1.27)
				)
				(justify left bottom)
				(hide yes)
			)
		)
		(pin "2"
		)
		(pin "1"
		)
		(instances
			(project "polarfire-som"
				(path ""
					(reference "R92")
					(unit 1)
				)
			)
		)
	)
	(symbol
		(lib_id "antmicroInterfaceControllers:DP83867ISRGZR")
		(at 138.43 59.69 0)
		(mirror y)
		(unit 1)
		(exclude_from_sim no)
		(in_bom yes)
		(on_board yes)
		(dnp no)
		(property "Reference" "U11"
			(at 120.65 52.07 0)
			(effects
				(font
					(size 1.27 1.27)
					(thickness 0.15)
				)
			)
		)
		(property "Value" "DP83867ISRGZR"
			(at 62.23 64.77 0)
			(effects
				(font
					(size 1.27 1.27)
					(thickness 0.15)
				)
				(justify left bottom)
				(hide yes)
			)
		)
		(property "Footprint" "antmicro-footprints:VQFN-48_7x7mm_P0.5mm_EP4.1x4.1mm"
			(at 62.23 67.31 0)
			(effects
				(font
					(size 1.27 1.27)
					(thickness 0.15)
				)
				(justify left bottom)
				(hide yes)
			)
		)
		(property "Datasheet" "https://www.ti.com/lit/ds/symlink/dp83867is.pdf?HQS=dis-dk-null-digikeymode-dsf-pf-null-wwe&ts=1704962980288&ref_url=https%253A%252F%252Fwww.ti.com%252Fgeneral%252Fdocs%252Fsuppproductinfo.tsp%253FdistId%253D10%2526gotoUrl%253Dhttps%253A%252F%252Fwww.ti.com%252Flit%252Fgpn%252Fdp83867is"
			(at 62.23 69.85 0)
			(effects
				(font
					(size 1.27 1.27)
					(thickness 0.15)
				)
				(justify left bottom)
				(hide yes)
			)
		)
		(property "Description" "Robust, High Immunity, Small Form Factor 10/100/1000 Ethernet, Physical Layer Transceiver, SGMII/RGMII"
			(at 138.43 59.69 0)
			(effects
				(font
					(size 1.27 1.27)
				)
				(hide yes)
			)
		)
		(property "Author" "Antmicro"
			(at 62.23 72.39 0)
			(effects
				(font
					(size 1.27 1.27)
					(thickness 0.15)
				)
				(justify left bottom)
				(hide yes)
			)
		)
		(property "License" "Apache-2.0"
			(at 62.23 74.93 0)
			(effects
				(font
					(size 1.27 1.27)
					(thickness 0.15)
				)
				(justify left bottom)
				(hide yes)
			)
		)
		(property "MPN" "DP83867ISRGZR"
			(at 120.65 54.61 0)
			(effects
				(font
					(size 1.27 1.27)
					(thickness 0.15)
				)
			)
		)
		(property "Manufacturer" "Texas Instruments"
			(at 62.23 72.39 0)
			(effects
				(font
					(size 1.27 1.27)
				)
				(justify left bottom)
				(hide yes)
			)
		)
		(pin "1"
		)
		(pin "10"
		)
		(pin "11"
		)
		(pin "12"
		)
		(pin "13"
		)
		(pin "14"
		)
		(pin "15"
		)
		(pin "16"
		)
		(pin "17"
		)
		(pin "18"
		)
		(pin "19"
		)
		(pin "2"
		)
		(pin "20"
		)
		(pin "21"
		)
		(pin "22"
		)
		(pin "23"
		)
		(pin "24"
		)
		(pin "25"
		)
		(pin "26"
		)
		(pin "27"
		)
		(pin "28"
		)
		(pin "29"
		)
		(pin "3"
		)
		(pin "30"
		)
		(pin "31"
		)
		(pin "32"
		)
		(pin "33"
		)
		(pin "34"
		)
		(pin "35"
		)
		(pin "36"
		)
		(pin "37"
		)
		(pin "38"
		)
		(pin "39"
		)
		(pin "4"
		)
		(pin "40"
		)
		(pin "41"
		)
		(pin "42"
		)
		(pin "43"
		)
		(pin "44"
		)
		(pin "45"
		)
		(pin "46"
		)
		(pin "47"
		)
		(pin "48"
		)
		(pin "49"
		)
		(pin "5"
		)
		(pin "6"
		)
		(pin "7"
		)
		(pin "8"
		)
		(pin "9"
		)
		(instances
			(project "polarfire-som"
				(path ""
					(reference "U11")
					(unit 1)
				)
			)
		)
	)
	(symbol
		(lib_id "antmicroCapacitors0402:C_100n_0402")
		(at 72.39 250.19 90)
		(unit 1)
		(exclude_from_sim no)
		(in_bom yes)
		(on_board yes)
		(dnp no)
		(property "Reference" "C191"
			(at 74.93 246.3735 90)
			(effects
				(font
					(size 1.27 1.27)
					(thickness 0.15)
				)
				(justify right)
			)
		)
		(property "Value" "C_100n_0402"
			(at 82.55 229.87 0)
			(effects
				(font
					(size 1.27 1.27)
					(thickness 0.15)
				)
				(justify left bottom)
				(hide yes)
			)
		)
		(property "Footprint" "antmicro-footprints:C_0402_1005Metric"
			(at 85.09 229.87 0)
			(effects
				(font
					(size 1.27 1.27)
					(thickness 0.15)
				)
				(justify left bottom)
				(hide yes)
			)
		)
		(property "Datasheet" "https://www.murata.com/products/productdetail?partno=GRM155R61H104KE14%23"
			(at 87.63 229.87 0)
			(effects
				(font
					(size 1.27 1.27)
					(thickness 0.15)
				)
				(justify left bottom)
				(hide yes)
			)
		)
		(property "Description" "SMD Multilayer Ceramic Capacitor, 0.1 µF, 50 V, 0402 [1005 Metric], ± 10%, X5R, GRM Series"
			(at 72.39 250.19 0)
			(effects
				(font
					(size 1.27 1.27)
				)
				(hide yes)
			)
		)
		(property "MPN" "GRM155R61H104KE14D"
			(at 90.17 229.87 0)
			(effects
				(font
					(size 1.27 1.27)
					(thickness 0.15)
				)
				(justify left bottom)
				(hide yes)
			)
		)
		(property "Manufacturer" "Murata"
			(at 92.71 229.87 0)
			(effects
				(font
					(size 1.27 1.27)
					(thickness 0.15)
				)
				(justify left bottom)
				(hide yes)
			)
		)
		(property "License" "Apache-2.0"
			(at 95.25 229.87 0)
			(effects
				(font
					(size 1.27 1.27)
					(thickness 0.15)
				)
				(justify left bottom)
				(hide yes)
			)
		)
		(property "Author" "Antmicro"
			(at 97.79 229.87 0)
			(effects
				(font
					(size 1.27 1.27)
					(thickness 0.15)
				)
				(justify left bottom)
				(hide yes)
			)
		)
		(property "Val" "100n"
			(at 80.01 248.285 90)
			(effects
				(font
					(size 1.27 1.27)
					(thickness 0.15)
				)
				(justify left bottom)
			)
		)
		(property "Voltage" "50V"
			(at 100.33 229.87 0)
			(effects
				(font
					(size 1.27 1.27)
				)
				(justify left bottom)
				(hide yes)
			)
		)
		(property "Dielectric" "X5R"
			(at 102.87 229.87 0)
			(effects
				(font
					(size 1.27 1.27)
				)
				(justify left bottom)
				(hide yes)
			)
		)
		(property "Public" ""
			(at 105.41 229.87 0)
			(effects
				(font
					(size 1.27 1.27)
				)
				(justify left bottom)
				(hide yes)
			)
		)
		(pin "1"
		)
		(pin "2"
		)
		(instances
			(project "polarfire-som"
				(path ""
					(reference "C191")
					(unit 1)
				)
			)
		)
	)
	(symbol
		(lib_id "antmicroResistors0402:R_4k7_0402")
		(at 330.2 195.58 90)
		(unit 1)
		(exclude_from_sim no)
		(in_bom yes)
		(on_board yes)
		(dnp no)
		(fields_autoplaced yes)
		(property "Reference" "R95"
			(at 332.74 191.77 90)
			(effects
				(font
					(size 1.27 1.27)
					(thickness 0.15)
				)
				(justify right)
			)
		)
		(property "Value" "R_4k7_0402"
			(at 342.9 175.26 0)
			(effects
				(font
					(size 1.27 1.27)
					(thickness 0.15)
				)
				(justify left bottom)
				(hide yes)
			)
		)
		(property "Footprint" "antmicro-footprints:R_0402_1005Metric"
			(at 345.44 175.26 0)
			(effects
				(font
					(size 1.27 1.27)
					(thickness 0.15)
				)
				(justify left bottom)
				(hide yes)
			)
		)
		(property "Datasheet" "https://www.bourns.com/docs/product-datasheets/cr.pdf"
			(at 347.98 175.26 0)
			(effects
				(font
					(size 1.27 1.27)
					(thickness 0.15)
				)
				(justify left bottom)
				(hide yes)
			)
		)
		(property "Description" "SMD Chip Resistor, 4.7 kohm, ± 1%, 62.5 mW, 0402 [1005 Metric], Thick Film, General Purpose"
			(at 330.2 195.58 0)
			(effects
				(font
					(size 1.27 1.27)
				)
				(hide yes)
			)
		)
		(property "MPN" "CR0402-FX-4701GLF"
			(at 350.52 175.26 0)
			(effects
				(font
					(size 1.27 1.27)
					(thickness 0.15)
				)
				(justify left bottom)
				(hide yes)
			)
		)
		(property "Manufacturer" "Bourns"
			(at 353.06 175.26 0)
			(effects
				(font
					(size 1.27 1.27)
					(thickness 0.15)
				)
				(justify left bottom)
				(hide yes)
			)
		)
		(property "License" "Apache-2.0"
			(at 355.6 175.26 0)
			(effects
				(font
					(size 1.27 1.27)
					(thickness 0.15)
				)
				(justify left bottom)
				(hide yes)
			)
		)
		(property "Author" "Antmicro"
			(at 358.14 175.26 0)
			(effects
				(font
					(size 1.27 1.27)
					(thickness 0.15)
				)
				(justify left bottom)
				(hide yes)
			)
		)
		(property "Val" "4k7"
			(at 332.74 194.31 90)
			(effects
				(font
					(size 1.27 1.27)
					(thickness 0.15)
				)
				(justify right)
			)
		)
		(property "Tolerance" "1%"
			(at 340.36 175.26 0)
			(effects
				(font
					(size 1.27 1.27)
				)
				(justify left bottom)
				(hide yes)
			)
		)
		(property "Public" ""
			(at 360.68 175.26 0)
			(effects
				(font
					(size 1.27 1.27)
				)
				(justify left bottom)
				(hide yes)
			)
		)
		(pin "2"
		)
		(pin "1"
		)
		(instances
			(project "polarfire-som"
				(path ""
					(reference "R95")
					(unit 1)
				)
			)
		)
	)
	(symbol
		(lib_id "antmicropower:+1V05")
		(at 153.67 66.04 0)
		(mirror y)
		(unit 1)
		(exclude_from_sim no)
		(in_bom yes)
		(on_board yes)
		(dnp no)
		(property "Reference" "#PWR0219"
			(at 153.67 69.85 0)
			(effects
				(font
					(size 1.27 1.27)
				)
				(hide yes)
			)
		)
		(property "Value" "+1V05"
			(at 153.67 62.23 0)
			(effects
				(font
					(size 1.27 1.27)
				)
			)
		)
		(property "Footprint" ""
			(at 153.67 66.04 0)
			(effects
				(font
					(size 1.27 1.27)
				)
				(hide yes)
			)
		)
		(property "Datasheet" ""
			(at 153.67 66.04 0)
			(effects
				(font
					(size 1.27 1.27)
				)
				(hide yes)
			)
		)
		(property "Description" ""
			(at 153.67 66.04 0)
			(effects
				(font
					(size 1.27 1.27)
				)
				(hide yes)
			)
		)
		(pin "1"
		)
		(instances
			(project "polarfire-som"
				(path ""
					(reference "#PWR0219")
					(unit 1)
				)
			)
		)
	)
	(symbol
		(lib_id "antmicroCapacitors0402:C_10n_0402")
		(at 105.41 193.04 90)
		(unit 1)
		(exclude_from_sim no)
		(in_bom yes)
		(on_board yes)
		(dnp no)
		(fields_autoplaced yes)
		(property "Reference" "C195"
			(at 107.95 189.2235 90)
			(effects
				(font
					(size 1.27 1.27)
					(thickness 0.15)
				)
				(justify right)
			)
		)
		(property "Value" "C_10n_0402"
			(at 115.57 172.72 0)
			(effects
				(font
					(size 1.27 1.27)
					(thickness 0.15)
				)
				(justify left bottom)
				(hide yes)
			)
		)
		(property "Footprint" "antmicro-footprints:C_0402_1005Metric"
			(at 118.11 172.72 0)
			(effects
				(font
					(size 1.27 1.27)
					(thickness 0.15)
				)
				(justify left bottom)
				(hide yes)
			)
		)
		(property "Datasheet" "https://www.murata.com/products/productdetail?partno=GRM155R71H103KA88%23"
			(at 120.65 172.72 0)
			(effects
				(font
					(size 1.27 1.27)
					(thickness 0.15)
				)
				(justify left bottom)
				(hide yes)
			)
		)
		(property "Description" "SMD Multilayer Ceramic Capacitor, 10000 pF, 50 V, 0402 [1005 Metric], ± 10%, X7R, GRM Series"
			(at 105.41 193.04 0)
			(effects
				(font
					(size 1.27 1.27)
				)
				(hide yes)
			)
		)
		(property "MPN" "GRM155R71H103KA88D"
			(at 123.19 172.72 0)
			(effects
				(font
					(size 1.27 1.27)
					(thickness 0.15)
				)
				(justify left bottom)
				(hide yes)
			)
		)
		(property "Manufacturer" "Murata"
			(at 125.73 172.72 0)
			(effects
				(font
					(size 1.27 1.27)
					(thickness 0.15)
				)
				(justify left bottom)
				(hide yes)
			)
		)
		(property "License" "Apache-2.0"
			(at 128.27 172.72 0)
			(effects
				(font
					(size 1.27 1.27)
					(thickness 0.15)
				)
				(justify left bottom)
				(hide yes)
			)
		)
		(property "Author" "Antmicro"
			(at 130.81 172.72 0)
			(effects
				(font
					(size 1.27 1.27)
					(thickness 0.15)
				)
				(justify left bottom)
				(hide yes)
			)
		)
		(property "Val" "10n"
			(at 107.95 191.7635 90)
			(effects
				(font
					(size 1.27 1.27)
					(thickness 0.15)
				)
				(justify right)
			)
		)
		(property "Voltage" "50V"
			(at 133.35 172.72 0)
			(effects
				(font
					(size 1.27 1.27)
				)
				(justify left bottom)
				(hide yes)
			)
		)
		(property "Dielectric" "X7R"
			(at 135.89 172.72 0)
			(effects
				(font
					(size 1.27 1.27)
				)
				(justify left bottom)
				(hide yes)
			)
		)
		(property "Public" ""
			(at 138.43 172.72 0)
			(effects
				(font
					(size 1.27 1.27)
				)
				(justify left bottom)
				(hide yes)
			)
		)
		(pin "1"
		)
		(pin "2"
		)
		(instances
			(project "polarfire-som"
				(path ""
					(reference "C195")
					(unit 1)
				)
			)
		)
	)
	(symbol
		(lib_id "antmicroResistors0402:R_11k_0402")
		(at 99.06 86.36 180)
		(unit 1)
		(exclude_from_sim no)
		(in_bom yes)
		(on_board yes)
		(dnp no)
		(property "Reference" "R67"
			(at 92.075 85.09 0)
			(effects
				(font
					(size 1.27 1.27)
					(thickness 0.15)
				)
			)
		)
		(property "Value" "R_11k_0402"
			(at 78.74 73.66 0)
			(effects
				(font
					(size 1.27 1.27)
					(thickness 0.15)
				)
				(justify left bottom)
				(hide yes)
			)
		)
		(property "Footprint" "antmicro-footprints:R_0402_1005Metric"
			(at 78.74 71.12 0)
			(effects
				(font
					(size 1.27 1.27)
					(thickness 0.15)
				)
				(justify left bottom)
				(hide yes)
			)
		)
		(property "Datasheet" "https://www.bourns.com/docs/product-datasheets/cr.pdf"
			(at 78.74 68.58 0)
			(effects
				(font
					(size 1.27 1.27)
					(thickness 0.15)
				)
				(justify left bottom)
				(hide yes)
			)
		)
		(property "Description" "SMD Chip Resistor, 11 kohm, ± 1%, 62.5 mW, 0402 [1005 Metric], Thick Film, General Purpose"
			(at 99.06 86.36 0)
			(effects
				(font
					(size 1.27 1.27)
				)
				(hide yes)
			)
		)
		(property "MPN" "CR0402-FX-1102GLF"
			(at 78.74 66.04 0)
			(effects
				(font
					(size 1.27 1.27)
					(thickness 0.15)
				)
				(justify left bottom)
				(hide yes)
			)
		)
		(property "Manufacturer" "Bourns"
			(at 78.74 63.5 0)
			(effects
				(font
					(size 1.27 1.27)
					(thickness 0.15)
				)
				(justify left bottom)
				(hide yes)
			)
		)
		(property "License" "Apache-2.0"
			(at 78.74 60.96 0)
			(effects
				(font
					(size 1.27 1.27)
					(thickness 0.15)
				)
				(justify left bottom)
				(hide yes)
			)
		)
		(property "Author" "Antmicro"
			(at 78.74 58.42 0)
			(effects
				(font
					(size 1.27 1.27)
					(thickness 0.15)
				)
				(justify left bottom)
				(hide yes)
			)
		)
		(property "Val" "11k"
			(at 100.965 85.09 0)
			(effects
				(font
					(size 1.27 1.27)
					(thickness 0.15)
				)
			)
		)
		(property "Tolerance" "1%"
			(at 78.74 76.2 0)
			(effects
				(font
					(size 1.27 1.27)
				)
				(justify left bottom)
				(hide yes)
			)
		)
		(property "Public" ""
			(at 78.74 55.88 0)
			(effects
				(font
					(size 1.27 1.27)
				)
				(justify left bottom)
				(hide yes)
			)
		)
		(pin "1"
		)
		(pin "2"
		)
		(instances
			(project "polarfire-som"
				(path ""
					(reference "R67")
					(unit 1)
				)
			)
		)
	)
	(symbol
		(lib_id "antmicropower:+1V05")
		(at 130.81 262.89 0)
		(unit 1)
		(exclude_from_sim no)
		(in_bom yes)
		(on_board yes)
		(dnp no)
		(property "Reference" "#PWR0242"
			(at 130.81 266.7 0)
			(effects
				(font
					(size 1.27 1.27)
				)
				(hide yes)
			)
		)
		(property "Value" "+1V05"
			(at 130.81 259.08 0)
			(effects
				(font
					(size 1.27 1.27)
				)
			)
		)
		(property "Footprint" ""
			(at 130.81 262.89 0)
			(effects
				(font
					(size 1.27 1.27)
				)
				(hide yes)
			)
		)
		(property "Datasheet" ""
			(at 130.81 262.89 0)
			(effects
				(font
					(size 1.27 1.27)
				)
				(hide yes)
			)
		)
		(property "Description" ""
			(at 130.81 262.89 0)
			(effects
				(font
					(size 1.27 1.27)
				)
				(hide yes)
			)
		)
		(pin "1"
		)
		(instances
			(project "polarfire-som"
				(path ""
					(reference "#PWR0242")
					(unit 1)
				)
			)
		)
	)
	(symbol
		(lib_id "antmicroCapacitors0402:C_10n_0402")
		(at 72.39 193.04 90)
		(unit 1)
		(exclude_from_sim no)
		(in_bom yes)
		(on_board yes)
		(dnp no)
		(fields_autoplaced yes)
		(property "Reference" "C254"
			(at 74.93 189.2235 90)
			(effects
				(font
					(size 1.27 1.27)
					(thickness 0.15)
				)
				(justify right)
			)
		)
		(property "Value" "C_10n_0402"
			(at 82.55 172.72 0)
			(effects
				(font
					(size 1.27 1.27)
					(thickness 0.15)
				)
				(justify left bottom)
				(hide yes)
			)
		)
		(property "Footprint" "antmicro-footprints:C_0402_1005Metric"
			(at 85.09 172.72 0)
			(effects
				(font
					(size 1.27 1.27)
					(thickness 0.15)
				)
				(justify left bottom)
				(hide yes)
			)
		)
		(property "Datasheet" "https://www.murata.com/products/productdetail?partno=GRM155R71H103KA88%23"
			(at 87.63 172.72 0)
			(effects
				(font
					(size 1.27 1.27)
					(thickness 0.15)
				)
				(justify left bottom)
				(hide yes)
			)
		)
		(property "Description" "SMD Multilayer Ceramic Capacitor, 10000 pF, 50 V, 0402 [1005 Metric], ± 10%, X7R, GRM Series"
			(at 72.39 193.04 0)
			(effects
				(font
					(size 1.27 1.27)
				)
				(hide yes)
			)
		)
		(property "MPN" "GRM155R71H103KA88D"
			(at 90.17 172.72 0)
			(effects
				(font
					(size 1.27 1.27)
					(thickness 0.15)
				)
				(justify left bottom)
				(hide yes)
			)
		)
		(property "Manufacturer" "Murata"
			(at 92.71 172.72 0)
			(effects
				(font
					(size 1.27 1.27)
					(thickness 0.15)
				)
				(justify left bottom)
				(hide yes)
			)
		)
		(property "License" "Apache-2.0"
			(at 95.25 172.72 0)
			(effects
				(font
					(size 1.27 1.27)
					(thickness 0.15)
				)
				(justify left bottom)
				(hide yes)
			)
		)
		(property "Author" "Antmicro"
			(at 97.79 172.72 0)
			(effects
				(font
					(size 1.27 1.27)
					(thickness 0.15)
				)
				(justify left bottom)
				(hide yes)
			)
		)
		(property "Val" "10n"
			(at 74.93 191.7635 90)
			(effects
				(font
					(size 1.27 1.27)
					(thickness 0.15)
				)
				(justify right)
			)
		)
		(property "Voltage" "50V"
			(at 100.33 172.72 0)
			(effects
				(font
					(size 1.27 1.27)
				)
				(justify left bottom)
				(hide yes)
			)
		)
		(property "Dielectric" "X7R"
			(at 102.87 172.72 0)
			(effects
				(font
					(size 1.27 1.27)
				)
				(justify left bottom)
				(hide yes)
			)
		)
		(property "Public" ""
			(at 105.41 172.72 0)
			(effects
				(font
					(size 1.27 1.27)
				)
				(justify left bottom)
				(hide yes)
			)
		)
		(pin "1"
		)
		(pin "2"
		)
		(instances
			(project "polarfire-som"
				(path ""
					(reference "C254")
					(unit 1)
				)
			)
		)
	)
	(symbol
		(lib_id "antmicropower:GND")
		(at 72.39 251.46 0)
		(unit 1)
		(exclude_from_sim no)
		(in_bom yes)
		(on_board yes)
		(dnp no)
		(property "Reference" "#PWR0224"
			(at 81.28 254 0)
			(effects
				(font
					(size 1.27 1.27)
					(thickness 0.15)
				)
				(justify left bottom)
				(hide yes)
			)
		)
		(property "Value" "GND"
			(at 72.39 255.27 0)
			(effects
				(font
					(size 1.27 1.27)
					(thickness 0.15)
				)
			)
		)
		(property "Footprint" ""
			(at 81.28 259.08 0)
			(effects
				(font
					(size 1.27 1.27)
					(thickness 0.15)
				)
				(justify left bottom)
				(hide yes)
			)
		)
		(property "Datasheet" ""
			(at 81.28 264.16 0)
			(effects
				(font
					(size 1.27 1.27)
					(thickness 0.15)
				)
				(justify left bottom)
				(hide yes)
			)
		)
		(property "Description" ""
			(at 72.39 251.46 0)
			(effects
				(font
					(size 1.27 1.27)
				)
				(hide yes)
			)
		)
		(property "Author" "Antmicro"
			(at 81.28 259.08 0)
			(effects
				(font
					(size 1.27 1.27)
					(thickness 0.15)
				)
				(justify left bottom)
				(hide yes)
			)
		)
		(property "License" "Apache-2.0"
			(at 81.28 261.62 0)
			(effects
				(font
					(size 1.27 1.27)
					(thickness 0.15)
				)
				(justify left bottom)
				(hide yes)
			)
		)
		(pin "1"
		)
		(instances
			(project "polarfire-som"
				(path ""
					(reference "#PWR0224")
					(unit 1)
				)
			)
		)
	)
	(symbol
		(lib_id "antmicropower:GND")
		(at 297.18 83.82 0)
		(unit 1)
		(exclude_from_sim no)
		(in_bom yes)
		(on_board yes)
		(dnp no)
		(property "Reference" "#PWR0180"
			(at 306.07 86.36 0)
			(effects
				(font
					(size 1.27 1.27)
					(thickness 0.15)
				)
				(justify left bottom)
				(hide yes)
			)
		)
		(property "Value" "GND"
			(at 297.18 87.63 0)
			(effects
				(font
					(size 1.27 1.27)
					(thickness 0.15)
				)
			)
		)
		(property "Footprint" ""
			(at 306.07 91.44 0)
			(effects
				(font
					(size 1.27 1.27)
					(thickness 0.15)
				)
				(justify left bottom)
				(hide yes)
			)
		)
		(property "Datasheet" ""
			(at 306.07 96.52 0)
			(effects
				(font
					(size 1.27 1.27)
					(thickness 0.15)
				)
				(justify left bottom)
				(hide yes)
			)
		)
		(property "Description" ""
			(at 297.18 83.82 0)
			(effects
				(font
					(size 1.27 1.27)
				)
				(hide yes)
			)
		)
		(property "Author" "Antmicro"
			(at 306.07 91.44 0)
			(effects
				(font
					(size 1.27 1.27)
					(thickness 0.15)
				)
				(justify left bottom)
				(hide yes)
			)
		)
		(property "License" "Apache-2.0"
			(at 306.07 93.98 0)
			(effects
				(font
					(size 1.27 1.27)
					(thickness 0.15)
				)
				(justify left bottom)
				(hide yes)
			)
		)
		(pin "1"
		)
		(instances
			(project "polarfire-som"
				(path ""
					(reference "#PWR0180")
					(unit 1)
				)
			)
		)
	)
	(symbol
		(lib_id "antmicropower:+3V3")
		(at 66.04 243.84 0)
		(unit 1)
		(exclude_from_sim no)
		(in_bom yes)
		(on_board yes)
		(dnp no)
		(fields_autoplaced yes)
		(property "Reference" "#PWR0299"
			(at 81.28 246.38 0)
			(effects
				(font
					(size 1.27 1.27)
					(thickness 0.15)
				)
				(justify left bottom)
				(hide yes)
			)
		)
		(property "Value" "+3V3"
			(at 66.04 238.76 0)
			(effects
				(font
					(size 1.27 1.27)
					(thickness 0.15)
				)
			)
		)
		(property "Footprint" ""
			(at 81.28 251.46 0)
			(effects
				(font
					(size 1.27 1.27)
					(thickness 0.15)
				)
				(justify left bottom)
				(hide yes)
			)
		)
		(property "Datasheet" ""
			(at 81.28 254 0)
			(effects
				(font
					(size 1.27 1.27)
					(thickness 0.15)
				)
				(justify left bottom)
				(hide yes)
			)
		)
		(property "Description" ""
			(at 66.04 243.84 0)
			(effects
				(font
					(size 1.27 1.27)
				)
				(hide yes)
			)
		)
		(property "Author" "Antmicro"
			(at 81.28 251.46 0)
			(effects
				(font
					(size 1.27 1.27)
					(thickness 0.15)
				)
				(justify left bottom)
				(hide yes)
			)
		)
		(property "License" "Apache-2.0"
			(at 81.28 254 0)
			(effects
				(font
					(size 1.27 1.27)
					(thickness 0.15)
				)
				(justify left bottom)
				(hide yes)
			)
		)
		(pin "1"
		)
		(instances
			(project "polarfire-som"
				(path ""
					(reference "#PWR0299")
					(unit 1)
				)
			)
		)
	)
	(symbol
		(lib_id "antmicropower:GND")
		(at 101.6 130.81 0)
		(unit 1)
		(exclude_from_sim no)
		(in_bom yes)
		(on_board yes)
		(dnp no)
		(property "Reference" "#PWR0244"
			(at 110.49 133.35 0)
			(effects
				(font
					(size 1.27 1.27)
					(thickness 0.15)
				)
				(justify left bottom)
				(hide yes)
			)
		)
		(property "Value" "GND"
			(at 101.6 134.62 0)
			(effects
				(font
					(size 1.27 1.27)
					(thickness 0.15)
				)
			)
		)
		(property "Footprint" ""
			(at 110.49 138.43 0)
			(effects
				(font
					(size 1.27 1.27)
					(thickness 0.15)
				)
				(justify left bottom)
				(hide yes)
			)
		)
		(property "Datasheet" ""
			(at 110.49 143.51 0)
			(effects
				(font
					(size 1.27 1.27)
					(thickness 0.15)
				)
				(justify left bottom)
				(hide yes)
			)
		)
		(property "Description" ""
			(at 101.6 130.81 0)
			(effects
				(font
					(size 1.27 1.27)
				)
				(hide yes)
			)
		)
		(property "Author" "Antmicro"
			(at 110.49 138.43 0)
			(effects
				(font
					(size 1.27 1.27)
					(thickness 0.15)
				)
				(justify left bottom)
				(hide yes)
			)
		)
		(property "License" "Apache-2.0"
			(at 110.49 140.97 0)
			(effects
				(font
					(size 1.27 1.27)
					(thickness 0.15)
				)
				(justify left bottom)
				(hide yes)
			)
		)
		(pin "1"
		)
		(instances
			(project "polarfire-som"
				(path ""
					(reference "#PWR0244")
					(unit 1)
				)
			)
		)
	)
	(symbol
		(lib_id "antmicroCapacitors0402:C_10u_0402")
		(at 130.81 193.04 270)
		(mirror x)
		(unit 1)
		(exclude_from_sim no)
		(in_bom yes)
		(on_board yes)
		(dnp no)
		(property "Reference" "C219"
			(at 128.27 189.23 90)
			(effects
				(font
					(size 1.27 1.27)
					(thickness 0.15)
				)
				(justify right)
			)
		)
		(property "Value" "C_10u_0402"
			(at 120.65 172.72 0)
			(effects
				(font
					(size 1.27 1.27)
					(thickness 0.15)
				)
				(justify left bottom)
				(hide yes)
			)
		)
		(property "Footprint" "antmicro-footprints:C_0402_1005Metric"
			(at 118.11 172.72 0)
			(effects
				(font
					(size 1.27 1.27)
					(thickness 0.15)
				)
				(justify left bottom)
				(hide yes)
			)
		)
		(property "Datasheet" "https://www.yageo.com/en/Chart/Download/pdf/CC0402MRX5R5BB106"
			(at 115.57 172.72 0)
			(effects
				(font
					(size 1.27 1.27)
					(thickness 0.15)
				)
				(justify left bottom)
				(hide yes)
			)
		)
		(property "Description" "SMD Multilayer Ceramic Capacitor, 10 µF, 6.3 V, 0402 [1005 Metric], ± 20%, X5R, CC Series"
			(at 130.81 193.04 0)
			(effects
				(font
					(size 1.27 1.27)
				)
				(hide yes)
			)
		)
		(property "MPN" "CC0402MRX5R5BB106"
			(at 113.03 172.72 0)
			(effects
				(font
					(size 1.27 1.27)
					(thickness 0.15)
				)
				(justify left bottom)
				(hide yes)
			)
		)
		(property "Manufacturer" "YAGEO"
			(at 110.49 172.72 0)
			(effects
				(font
					(size 1.27 1.27)
					(thickness 0.15)
				)
				(justify left bottom)
				(hide yes)
			)
		)
		(property "License" "Apache-2.0"
			(at 107.95 172.72 0)
			(effects
				(font
					(size 1.27 1.27)
					(thickness 0.15)
				)
				(justify left bottom)
				(hide yes)
			)
		)
		(property "Author" "Antmicro"
			(at 105.41 172.72 0)
			(effects
				(font
					(size 1.27 1.27)
					(thickness 0.15)
				)
				(justify left bottom)
				(hide yes)
			)
		)
		(property "Val" "10u"
			(at 128.27 191.77 90)
			(effects
				(font
					(size 1.27 1.27)
					(thickness 0.15)
				)
				(justify right)
			)
		)
		(property "Voltage" ""
			(at 102.87 172.72 0)
			(effects
				(font
					(size 1.27 1.27)
				)
				(justify left bottom)
				(hide yes)
			)
		)
		(property "Dielectric" ""
			(at 100.33 172.72 0)
			(effects
				(font
					(size 1.27 1.27)
				)
				(justify left bottom)
				(hide yes)
			)
		)
		(property "Public" ""
			(at 97.79 172.72 0)
			(effects
				(font
					(size 1.27 1.27)
				)
				(justify left bottom)
				(hide yes)
			)
		)
		(pin "1"
		)
		(pin "2"
		)
		(instances
			(project "polarfire-som"
				(path ""
					(reference "C219")
					(unit 1)
				)
			)
		)
	)
	(symbol
		(lib_id "antmicroCapacitors0402:C_1u_0402")
		(at 66.04 231.14 270)
		(mirror x)
		(unit 1)
		(exclude_from_sim no)
		(in_bom yes)
		(on_board yes)
		(dnp no)
		(fields_autoplaced yes)
		(property "Reference" "C115"
			(at 63.5 227.3235 90)
			(effects
				(font
					(size 1.27 1.27)
					(thickness 0.15)
				)
				(justify right)
			)
		)
		(property "Value" "C_1u_0402"
			(at 55.88 210.82 0)
			(effects
				(font
					(size 1.27 1.27)
					(thickness 0.15)
				)
				(justify left bottom)
				(hide yes)
			)
		)
		(property "Footprint" "antmicro-footprints:C_0402_1005Metric"
			(at 53.34 210.82 0)
			(effects
				(font
					(size 1.27 1.27)
					(thickness 0.15)
				)
				(justify left bottom)
				(hide yes)
			)
		)
		(property "Datasheet" "https://product.tdk.com/en/search/capacitor/ceramic/mlcc/info?part_no=C1005X6S1A105K050BC"
			(at 50.8 210.82 0)
			(effects
				(font
					(size 1.27 1.27)
					(thickness 0.15)
				)
				(justify left bottom)
				(hide yes)
			)
		)
		(property "Description" "SMD Multilayer Ceramic Capacitor, 1 µF, 10 V, 0402 [1005 Metric], ± 10%, X6S, C"
			(at 66.04 231.14 0)
			(effects
				(font
					(size 1.27 1.27)
				)
				(hide yes)
			)
		)
		(property "MPN" "C1005X6S1A105K050BC"
			(at 48.26 210.82 0)
			(effects
				(font
					(size 1.27 1.27)
					(thickness 0.15)
				)
				(justify left bottom)
				(hide yes)
			)
		)
		(property "Manufacturer" "TDK"
			(at 45.72 210.82 0)
			(effects
				(font
					(size 1.27 1.27)
					(thickness 0.15)
				)
				(justify left bottom)
				(hide yes)
			)
		)
		(property "License" "Apache-2.0"
			(at 43.18 210.82 0)
			(effects
				(font
					(size 1.27 1.27)
					(thickness 0.15)
				)
				(justify left bottom)
				(hide yes)
			)
		)
		(property "Author" "Antmicro"
			(at 40.64 210.82 0)
			(effects
				(font
					(size 1.27 1.27)
					(thickness 0.15)
				)
				(justify left bottom)
				(hide yes)
			)
		)
		(property "Val" "1u"
			(at 63.5 229.8635 90)
			(effects
				(font
					(size 1.27 1.27)
					(thickness 0.15)
				)
				(justify right)
			)
		)
		(property "Voltage" ""
			(at 38.1 210.82 0)
			(effects
				(font
					(size 1.27 1.27)
				)
				(justify left bottom)
				(hide yes)
			)
		)
		(property "Dielectric" ""
			(at 35.56 210.82 0)
			(effects
				(font
					(size 1.27 1.27)
				)
				(justify left bottom)
				(hide yes)
			)
		)
		(property "Public" ""
			(at 33.02 210.82 0)
			(effects
				(font
					(size 1.27 1.27)
				)
				(justify left bottom)
				(hide yes)
			)
		)
		(pin "1"
		)
		(pin "2"
		)
		(instances
			(project "polarfire-som"
				(path ""
					(reference "C115")
					(unit 1)
				)
			)
		)
	)
	(symbol
		(lib_id "antmicroCapacitors0402:C_100n_0402")
		(at 297.18 81.28 90)
		(unit 1)
		(exclude_from_sim no)
		(in_bom yes)
		(on_board yes)
		(dnp no)
		(property "Reference" "C239"
			(at 299.72 77.4635 90)
			(effects
				(font
					(size 1.27 1.27)
					(thickness 0.15)
				)
				(justify right)
			)
		)
		(property "Value" "C_100n_0402"
			(at 307.34 60.96 0)
			(effects
				(font
					(size 1.27 1.27)
					(thickness 0.15)
				)
				(justify left bottom)
				(hide yes)
			)
		)
		(property "Footprint" "antmicro-footprints:C_0402_1005Metric"
			(at 309.88 60.96 0)
			(effects
				(font
					(size 1.27 1.27)
					(thickness 0.15)
				)
				(justify left bottom)
				(hide yes)
			)
		)
		(property "Datasheet" "https://www.murata.com/products/productdetail?partno=GRM155R61H104KE14%23"
			(at 312.42 60.96 0)
			(effects
				(font
					(size 1.27 1.27)
					(thickness 0.15)
				)
				(justify left bottom)
				(hide yes)
			)
		)
		(property "Description" "SMD Multilayer Ceramic Capacitor, 0.1 µF, 50 V, 0402 [1005 Metric], ± 10%, X5R, GRM Series"
			(at 297.18 81.28 0)
			(effects
				(font
					(size 1.27 1.27)
				)
				(hide yes)
			)
		)
		(property "MPN" "GRM155R61H104KE14D"
			(at 314.96 60.96 0)
			(effects
				(font
					(size 1.27 1.27)
					(thickness 0.15)
				)
				(justify left bottom)
				(hide yes)
			)
		)
		(property "Manufacturer" "Murata"
			(at 317.5 60.96 0)
			(effects
				(font
					(size 1.27 1.27)
					(thickness 0.15)
				)
				(justify left bottom)
				(hide yes)
			)
		)
		(property "License" "Apache-2.0"
			(at 320.04 60.96 0)
			(effects
				(font
					(size 1.27 1.27)
					(thickness 0.15)
				)
				(justify left bottom)
				(hide yes)
			)
		)
		(property "Author" "Antmicro"
			(at 322.58 60.96 0)
			(effects
				(font
					(size 1.27 1.27)
					(thickness 0.15)
				)
				(justify left bottom)
				(hide yes)
			)
		)
		(property "Val" "100n"
			(at 304.8 79.375 90)
			(effects
				(font
					(size 1.27 1.27)
					(thickness 0.15)
				)
				(justify left bottom)
			)
		)
		(property "Voltage" "50V"
			(at 325.12 60.96 0)
			(effects
				(font
					(size 1.27 1.27)
				)
				(justify left bottom)
				(hide yes)
			)
		)
		(property "Dielectric" "X5R"
			(at 327.66 60.96 0)
			(effects
				(font
					(size 1.27 1.27)
				)
				(justify left bottom)
				(hide yes)
			)
		)
		(property "Public" ""
			(at 330.2 60.96 0)
			(effects
				(font
					(size 1.27 1.27)
				)
				(justify left bottom)
				(hide yes)
			)
		)
		(pin "1"
		)
		(pin "2"
		)
		(instances
			(project "polarfire-som"
				(path ""
					(reference "C239")
					(unit 1)
				)
			)
		)
	)
	(symbol
		(lib_id "antmicroCapacitors0402:C_10u_0402")
		(at 99.06 193.04 270)
		(mirror x)
		(unit 1)
		(exclude_from_sim no)
		(in_bom yes)
		(on_board yes)
		(dnp no)
		(property "Reference" "C192"
			(at 96.52 189.23 90)
			(effects
				(font
					(size 1.27 1.27)
					(thickness 0.15)
				)
				(justify right)
			)
		)
		(property "Value" "C_10u_0402"
			(at 88.9 172.72 0)
			(effects
				(font
					(size 1.27 1.27)
					(thickness 0.15)
				)
				(justify left bottom)
				(hide yes)
			)
		)
		(property "Footprint" "antmicro-footprints:C_0402_1005Metric"
			(at 86.36 172.72 0)
			(effects
				(font
					(size 1.27 1.27)
					(thickness 0.15)
				)
				(justify left bottom)
				(hide yes)
			)
		)
		(property "Datasheet" "https://www.yageo.com/en/Chart/Download/pdf/CC0402MRX5R5BB106"
			(at 83.82 172.72 0)
			(effects
				(font
					(size 1.27 1.27)
					(thickness 0.15)
				)
				(justify left bottom)
				(hide yes)
			)
		)
		(property "Description" "SMD Multilayer Ceramic Capacitor, 10 µF, 6.3 V, 0402 [1005 Metric], ± 20%, X5R, CC Series"
			(at 99.06 193.04 0)
			(effects
				(font
					(size 1.27 1.27)
				)
				(hide yes)
			)
		)
		(property "MPN" "CC0402MRX5R5BB106"
			(at 81.28 172.72 0)
			(effects
				(font
					(size 1.27 1.27)
					(thickness 0.15)
				)
				(justify left bottom)
				(hide yes)
			)
		)
		(property "Manufacturer" "YAGEO"
			(at 78.74 172.72 0)
			(effects
				(font
					(size 1.27 1.27)
					(thickness 0.15)
				)
				(justify left bottom)
				(hide yes)
			)
		)
		(property "License" "Apache-2.0"
			(at 76.2 172.72 0)
			(effects
				(font
					(size 1.27 1.27)
					(thickness 0.15)
				)
				(justify left bottom)
				(hide yes)
			)
		)
		(property "Author" "Antmicro"
			(at 73.66 172.72 0)
			(effects
				(font
					(size 1.27 1.27)
					(thickness 0.15)
				)
				(justify left bottom)
				(hide yes)
			)
		)
		(property "Val" "10u"
			(at 96.52 191.77 90)
			(effects
				(font
					(size 1.27 1.27)
					(thickness 0.15)
				)
				(justify right)
			)
		)
		(property "Voltage" ""
			(at 71.12 172.72 0)
			(effects
				(font
					(size 1.27 1.27)
				)
				(justify left bottom)
				(hide yes)
			)
		)
		(property "Dielectric" ""
			(at 68.58 172.72 0)
			(effects
				(font
					(size 1.27 1.27)
				)
				(justify left bottom)
				(hide yes)
			)
		)
		(property "Public" ""
			(at 66.04 172.72 0)
			(effects
				(font
					(size 1.27 1.27)
				)
				(justify left bottom)
				(hide yes)
			)
		)
		(pin "1"
		)
		(pin "2"
		)
		(instances
			(project "polarfire-som"
				(path ""
					(reference "C192")
					(unit 1)
				)
			)
		)
	)
	(symbol
		(lib_id "antmicroResistors0402:R_10k_0402")
		(at 313.69 195.58 90)
		(unit 1)
		(exclude_from_sim no)
		(in_bom yes)
		(on_board yes)
		(dnp no)
		(property "Reference" "R102"
			(at 316.23 191.77 90)
			(effects
				(font
					(size 1.27 1.27)
					(thickness 0.15)
				)
				(justify right)
			)
		)
		(property "Value" "R_10k_0402"
			(at 326.39 175.26 0)
			(effects
				(font
					(size 1.27 1.27)
					(thickness 0.15)
				)
				(justify left bottom)
				(hide yes)
			)
		)
		(property "Footprint" "antmicro-footprints:R_0402_1005Metric"
			(at 328.93 175.26 0)
			(effects
				(font
					(size 1.27 1.27)
					(thickness 0.15)
				)
				(justify left bottom)
				(hide yes)
			)
		)
		(property "Datasheet" "https://www.bourns.com/docs/product-datasheets/cr.pdf"
			(at 331.47 175.26 0)
			(effects
				(font
					(size 1.27 1.27)
					(thickness 0.15)
				)
				(justify left bottom)
				(hide yes)
			)
		)
		(property "Description" "SMD Chip Resistor, 10 kohm, ± 1%, 62.5 mW, 0402 [1005 Metric], Thick Film, General Purpose"
			(at 313.69 195.58 0)
			(effects
				(font
					(size 1.27 1.27)
				)
				(hide yes)
			)
		)
		(property "MPN" "CR0402-FX-1002GLF"
			(at 334.01 175.26 0)
			(effects
				(font
					(size 1.27 1.27)
					(thickness 0.15)
				)
				(justify left bottom)
				(hide yes)
			)
		)
		(property "Manufacturer" "Bourns"
			(at 336.55 175.26 0)
			(effects
				(font
					(size 1.27 1.27)
					(thickness 0.15)
				)
				(justify left bottom)
				(hide yes)
			)
		)
		(property "License" "Apache-2.0"
			(at 339.09 175.26 0)
			(effects
				(font
					(size 1.27 1.27)
					(thickness 0.15)
				)
				(justify left bottom)
				(hide yes)
			)
		)
		(property "Author" "Antmicro"
			(at 341.63 175.26 0)
			(effects
				(font
					(size 1.27 1.27)
					(thickness 0.15)
				)
				(justify left bottom)
				(hide yes)
			)
		)
		(property "Val" "10k"
			(at 316.23 194.31 90)
			(effects
				(font
					(size 1.27 1.27)
					(thickness 0.15)
				)
				(justify right)
			)
		)
		(property "Tolerance" "1%"
			(at 323.85 175.26 0)
			(effects
				(font
					(size 1.27 1.27)
				)
				(justify left bottom)
				(hide yes)
			)
		)
		(property "Public" ""
			(at 344.17 175.26 0)
			(effects
				(font
					(size 1.27 1.27)
				)
				(justify left bottom)
				(hide yes)
			)
		)
		(pin "1"
		)
		(pin "2"
		)
		(instances
			(project "polarfire-som"
				(path ""
					(reference "R102")
					(unit 1)
				)
			)
		)
	)
	(symbol
		(lib_id "antmicroCapacitors0402:C_100n_0402")
		(at 130.81 250.19 90)
		(unit 1)
		(exclude_from_sim no)
		(in_bom yes)
		(on_board yes)
		(dnp no)
		(property "Reference" "C252"
			(at 133.35 246.3735 90)
			(effects
				(font
					(size 1.27 1.27)
					(thickness 0.15)
				)
				(justify right)
			)
		)
		(property "Value" "C_100n_0402"
			(at 140.97 229.87 0)
			(effects
				(font
					(size 1.27 1.27)
					(thickness 0.15)
				)
				(justify left bottom)
				(hide yes)
			)
		)
		(property "Footprint" "antmicro-footprints:C_0402_1005Metric"
			(at 143.51 229.87 0)
			(effects
				(font
					(size 1.27 1.27)
					(thickness 0.15)
				)
				(justify left bottom)
				(hide yes)
			)
		)
		(property "Datasheet" "https://www.murata.com/products/productdetail?partno=GRM155R61H104KE14%23"
			(at 146.05 229.87 0)
			(effects
				(font
					(size 1.27 1.27)
					(thickness 0.15)
				)
				(justify left bottom)
				(hide yes)
			)
		)
		(property "Description" "SMD Multilayer Ceramic Capacitor, 0.1 µF, 50 V, 0402 [1005 Metric], ± 10%, X5R, GRM Series"
			(at 130.81 250.19 0)
			(effects
				(font
					(size 1.27 1.27)
				)
				(hide yes)
			)
		)
		(property "MPN" "GRM155R61H104KE14D"
			(at 148.59 229.87 0)
			(effects
				(font
					(size 1.27 1.27)
					(thickness 0.15)
				)
				(justify left bottom)
				(hide yes)
			)
		)
		(property "Manufacturer" "Murata"
			(at 151.13 229.87 0)
			(effects
				(font
					(size 1.27 1.27)
					(thickness 0.15)
				)
				(justify left bottom)
				(hide yes)
			)
		)
		(property "License" "Apache-2.0"
			(at 153.67 229.87 0)
			(effects
				(font
					(size 1.27 1.27)
					(thickness 0.15)
				)
				(justify left bottom)
				(hide yes)
			)
		)
		(property "Author" "Antmicro"
			(at 156.21 229.87 0)
			(effects
				(font
					(size 1.27 1.27)
					(thickness 0.15)
				)
				(justify left bottom)
				(hide yes)
			)
		)
		(property "Val" "100n"
			(at 138.43 248.285 90)
			(effects
				(font
					(size 1.27 1.27)
					(thickness 0.15)
				)
				(justify left bottom)
			)
		)
		(property "Voltage" "50V"
			(at 158.75 229.87 0)
			(effects
				(font
					(size 1.27 1.27)
				)
				(justify left bottom)
				(hide yes)
			)
		)
		(property "Dielectric" "X5R"
			(at 161.29 229.87 0)
			(effects
				(font
					(size 1.27 1.27)
				)
				(justify left bottom)
				(hide yes)
			)
		)
		(property "Public" ""
			(at 163.83 229.87 0)
			(effects
				(font
					(size 1.27 1.27)
				)
				(justify left bottom)
				(hide yes)
			)
		)
		(pin "1"
		)
		(pin "2"
		)
		(instances
			(project "polarfire-som"
				(path ""
					(reference "C252")
					(unit 1)
				)
			)
		)
	)
	(symbol
		(lib_id "antmicroCapacitors0402:C_100n_0402")
		(at 72.39 212.09 90)
		(unit 1)
		(exclude_from_sim no)
		(in_bom yes)
		(on_board yes)
		(dnp no)
		(property "Reference" "C117"
			(at 74.93 208.2735 90)
			(effects
				(font
					(size 1.27 1.27)
					(thickness 0.15)
				)
				(justify right)
			)
		)
		(property "Value" "C_100n_0402"
			(at 82.55 191.77 0)
			(effects
				(font
					(size 1.27 1.27)
					(thickness 0.15)
				)
				(justify left bottom)
				(hide yes)
			)
		)
		(property "Footprint" "antmicro-footprints:C_0402_1005Metric"
			(at 85.09 191.77 0)
			(effects
				(font
					(size 1.27 1.27)
					(thickness 0.15)
				)
				(justify left bottom)
				(hide yes)
			)
		)
		(property "Datasheet" "https://www.murata.com/products/productdetail?partno=GRM155R61H104KE14%23"
			(at 87.63 191.77 0)
			(effects
				(font
					(size 1.27 1.27)
					(thickness 0.15)
				)
				(justify left bottom)
				(hide yes)
			)
		)
		(property "Description" "SMD Multilayer Ceramic Capacitor, 0.1 µF, 50 V, 0402 [1005 Metric], ± 10%, X5R, GRM Series"
			(at 72.39 212.09 0)
			(effects
				(font
					(size 1.27 1.27)
				)
				(hide yes)
			)
		)
		(property "MPN" "GRM155R61H104KE14D"
			(at 90.17 191.77 0)
			(effects
				(font
					(size 1.27 1.27)
					(thickness 0.15)
				)
				(justify left bottom)
				(hide yes)
			)
		)
		(property "Manufacturer" "Murata"
			(at 92.71 191.77 0)
			(effects
				(font
					(size 1.27 1.27)
					(thickness 0.15)
				)
				(justify left bottom)
				(hide yes)
			)
		)
		(property "License" "Apache-2.0"
			(at 95.25 191.77 0)
			(effects
				(font
					(size 1.27 1.27)
					(thickness 0.15)
				)
				(justify left bottom)
				(hide yes)
			)
		)
		(property "Author" "Antmicro"
			(at 97.79 191.77 0)
			(effects
				(font
					(size 1.27 1.27)
					(thickness 0.15)
				)
				(justify left bottom)
				(hide yes)
			)
		)
		(property "Val" "100n"
			(at 80.01 210.185 90)
			(effects
				(font
					(size 1.27 1.27)
					(thickness 0.15)
				)
				(justify left bottom)
			)
		)
		(property "Voltage" "50V"
			(at 100.33 191.77 0)
			(effects
				(font
					(size 1.27 1.27)
				)
				(justify left bottom)
				(hide yes)
			)
		)
		(property "Dielectric" "X5R"
			(at 102.87 191.77 0)
			(effects
				(font
					(size 1.27 1.27)
				)
				(justify left bottom)
				(hide yes)
			)
		)
		(property "Public" ""
			(at 105.41 191.77 0)
			(effects
				(font
					(size 1.27 1.27)
				)
				(justify left bottom)
				(hide yes)
			)
		)
		(pin "1"
		)
		(pin "2"
		)
		(instances
			(project "polarfire-som"
				(path ""
					(reference "C117")
					(unit 1)
				)
			)
		)
	)
	(symbol
		(lib_id "antmicropower:GND")
		(at 130.81 251.46 0)
		(unit 1)
		(exclude_from_sim no)
		(in_bom yes)
		(on_board yes)
		(dnp no)
		(property "Reference" "#PWR0241"
			(at 139.7 254 0)
			(effects
				(font
					(size 1.27 1.27)
					(thickness 0.15)
				)
				(justify left bottom)
				(hide yes)
			)
		)
		(property "Value" "GND"
			(at 130.81 255.27 0)
			(effects
				(font
					(size 1.27 1.27)
					(thickness 0.15)
				)
			)
		)
		(property "Footprint" ""
			(at 139.7 259.08 0)
			(effects
				(font
					(size 1.27 1.27)
					(thickness 0.15)
				)
				(justify left bottom)
				(hide yes)
			)
		)
		(property "Datasheet" ""
			(at 139.7 264.16 0)
			(effects
				(font
					(size 1.27 1.27)
					(thickness 0.15)
				)
				(justify left bottom)
				(hide yes)
			)
		)
		(property "Description" ""
			(at 130.81 251.46 0)
			(effects
				(font
					(size 1.27 1.27)
				)
				(hide yes)
			)
		)
		(property "Author" "Antmicro"
			(at 139.7 259.08 0)
			(effects
				(font
					(size 1.27 1.27)
					(thickness 0.15)
				)
				(justify left bottom)
				(hide yes)
			)
		)
		(property "License" "Apache-2.0"
			(at 139.7 261.62 0)
			(effects
				(font
					(size 1.27 1.27)
					(thickness 0.15)
				)
				(justify left bottom)
				(hide yes)
			)
		)
		(pin "1"
		)
		(instances
			(project "polarfire-som"
				(path ""
					(reference "#PWR0241")
					(unit 1)
				)
			)
		)
	)
	(symbol
		(lib_id "antmicropower:+3V3")
		(at 195.58 113.03 270)
		(unit 1)
		(exclude_from_sim no)
		(in_bom yes)
		(on_board yes)
		(dnp no)
		(property "Reference" "#PWR0257"
			(at 193.04 128.27 0)
			(effects
				(font
					(size 1.27 1.27)
					(thickness 0.15)
				)
				(justify left bottom)
				(hide yes)
			)
		)
		(property "Value" "+3V3"
			(at 201.93 113.03 90)
			(effects
				(font
					(size 1.27 1.27)
					(thickness 0.15)
				)
			)
		)
		(property "Footprint" ""
			(at 187.96 128.27 0)
			(effects
				(font
					(size 1.27 1.27)
					(thickness 0.15)
				)
				(justify left bottom)
				(hide yes)
			)
		)
		(property "Datasheet" ""
			(at 185.42 128.27 0)
			(effects
				(font
					(size 1.27 1.27)
					(thickness 0.15)
				)
				(justify left bottom)
				(hide yes)
			)
		)
		(property "Description" ""
			(at 195.58 113.03 0)
			(effects
				(font
					(size 1.27 1.27)
				)
				(hide yes)
			)
		)
		(property "Author" "Antmicro"
			(at 187.96 128.27 0)
			(effects
				(font
					(size 1.27 1.27)
					(thickness 0.15)
				)
				(justify left bottom)
				(hide yes)
			)
		)
		(property "License" "Apache-2.0"
			(at 185.42 128.27 0)
			(effects
				(font
					(size 1.27 1.27)
					(thickness 0.15)
				)
				(justify left bottom)
				(hide yes)
			)
		)
		(pin "1"
		)
		(instances
			(project "polarfire-som"
				(path ""
					(reference "#PWR0257")
					(unit 1)
				)
			)
		)
	)
	(symbol
		(lib_id "antmicroCapacitors0402:C_1u_0402")
		(at 99.06 231.14 270)
		(mirror x)
		(unit 1)
		(exclude_from_sim no)
		(in_bom yes)
		(on_board yes)
		(dnp no)
		(fields_autoplaced yes)
		(property "Reference" "C194"
			(at 96.52 227.3235 90)
			(effects
				(font
					(size 1.27 1.27)
					(thickness 0.15)
				)
				(justify right)
			)
		)
		(property "Value" "C_1u_0402"
			(at 88.9 210.82 0)
			(effects
				(font
					(size 1.27 1.27)
					(thickness 0.15)
				)
				(justify left bottom)
				(hide yes)
			)
		)
		(property "Footprint" "antmicro-footprints:C_0402_1005Metric"
			(at 86.36 210.82 0)
			(effects
				(font
					(size 1.27 1.27)
					(thickness 0.15)
				)
				(justify left bottom)
				(hide yes)
			)
		)
		(property "Datasheet" "https://product.tdk.com/en/search/capacitor/ceramic/mlcc/info?part_no=C1005X6S1A105K050BC"
			(at 83.82 210.82 0)
			(effects
				(font
					(size 1.27 1.27)
					(thickness 0.15)
				)
				(justify left bottom)
				(hide yes)
			)
		)
		(property "Description" "SMD Multilayer Ceramic Capacitor, 1 µF, 10 V, 0402 [1005 Metric], ± 10%, X6S, C"
			(at 99.06 231.14 0)
			(effects
				(font
					(size 1.27 1.27)
				)
				(hide yes)
			)
		)
		(property "MPN" "C1005X6S1A105K050BC"
			(at 81.28 210.82 0)
			(effects
				(font
					(size 1.27 1.27)
					(thickness 0.15)
				)
				(justify left bottom)
				(hide yes)
			)
		)
		(property "Manufacturer" "TDK"
			(at 78.74 210.82 0)
			(effects
				(font
					(size 1.27 1.27)
					(thickness 0.15)
				)
				(justify left bottom)
				(hide yes)
			)
		)
		(property "License" "Apache-2.0"
			(at 76.2 210.82 0)
			(effects
				(font
					(size 1.27 1.27)
					(thickness 0.15)
				)
				(justify left bottom)
				(hide yes)
			)
		)
		(property "Author" "Antmicro"
			(at 73.66 210.82 0)
			(effects
				(font
					(size 1.27 1.27)
					(thickness 0.15)
				)
				(justify left bottom)
				(hide yes)
			)
		)
		(property "Val" "1u"
			(at 96.52 229.8635 90)
			(effects
				(font
					(size 1.27 1.27)
					(thickness 0.15)
				)
				(justify right)
			)
		)
		(property "Voltage" ""
			(at 71.12 210.82 0)
			(effects
				(font
					(size 1.27 1.27)
				)
				(justify left bottom)
				(hide yes)
			)
		)
		(property "Dielectric" ""
			(at 68.58 210.82 0)
			(effects
				(font
					(size 1.27 1.27)
				)
				(justify left bottom)
				(hide yes)
			)
		)
		(property "Public" ""
			(at 66.04 210.82 0)
			(effects
				(font
					(size 1.27 1.27)
				)
				(justify left bottom)
				(hide yes)
			)
		)
		(pin "1"
		)
		(pin "2"
		)
		(instances
			(project "polarfire-som"
				(path ""
					(reference "C194")
					(unit 1)
				)
			)
		)
	)
	(symbol
		(lib_id "antmicropower:+3V3")
		(at 297.18 73.66 0)
		(unit 1)
		(exclude_from_sim no)
		(in_bom yes)
		(on_board yes)
		(dnp no)
		(fields_autoplaced yes)
		(property "Reference" "#PWR0181"
			(at 312.42 76.2 0)
			(effects
				(font
					(size 1.27 1.27)
					(thickness 0.15)
				)
				(justify left bottom)
				(hide yes)
			)
		)
		(property "Value" "+3V3"
			(at 297.18 68.58 0)
			(effects
				(font
					(size 1.27 1.27)
					(thickness 0.15)
				)
			)
		)
		(property "Footprint" ""
			(at 312.42 81.28 0)
			(effects
				(font
					(size 1.27 1.27)
					(thickness 0.15)
				)
				(justify left bottom)
				(hide yes)
			)
		)
		(property "Datasheet" ""
			(at 312.42 83.82 0)
			(effects
				(font
					(size 1.27 1.27)
					(thickness 0.15)
				)
				(justify left bottom)
				(hide yes)
			)
		)
		(property "Description" ""
			(at 297.18 73.66 0)
			(effects
				(font
					(size 1.27 1.27)
				)
				(hide yes)
			)
		)
		(property "Author" "Antmicro"
			(at 312.42 81.28 0)
			(effects
				(font
					(size 1.27 1.27)
					(thickness 0.15)
				)
				(justify left bottom)
				(hide yes)
			)
		)
		(property "License" "Apache-2.0"
			(at 312.42 83.82 0)
			(effects
				(font
					(size 1.27 1.27)
					(thickness 0.15)
				)
				(justify left bottom)
				(hide yes)
			)
		)
		(pin "1"
		)
		(instances
			(project "polarfire-som"
				(path ""
					(reference "#PWR0181")
					(unit 1)
				)
			)
		)
	)
	(symbol
		(lib_id "antmicropower:GND")
		(at 158.75 88.9 0)
		(unit 1)
		(exclude_from_sim no)
		(in_bom yes)
		(on_board yes)
		(dnp no)
		(property "Reference" "#PWR0262"
			(at 167.64 91.44 0)
			(effects
				(font
					(size 1.27 1.27)
					(thickness 0.15)
				)
				(justify left bottom)
				(hide yes)
			)
		)
		(property "Value" "GND"
			(at 158.75 92.71 0)
			(effects
				(font
					(size 1.27 1.27)
					(thickness 0.15)
				)
			)
		)
		(property "Footprint" ""
			(at 167.64 96.52 0)
			(effects
				(font
					(size 1.27 1.27)
					(thickness 0.15)
				)
				(justify left bottom)
				(hide yes)
			)
		)
		(property "Datasheet" ""
			(at 167.64 101.6 0)
			(effects
				(font
					(size 1.27 1.27)
					(thickness 0.15)
				)
				(justify left bottom)
				(hide yes)
			)
		)
		(property "Description" ""
			(at 158.75 88.9 0)
			(effects
				(font
					(size 1.27 1.27)
				)
				(hide yes)
			)
		)
		(property "Author" "Antmicro"
			(at 167.64 96.52 0)
			(effects
				(font
					(size 1.27 1.27)
					(thickness 0.15)
				)
				(justify left bottom)
				(hide yes)
			)
		)
		(property "License" "Apache-2.0"
			(at 167.64 99.06 0)
			(effects
				(font
					(size 1.27 1.27)
					(thickness 0.15)
				)
				(justify left bottom)
				(hide yes)
			)
		)
		(pin "1"
		)
		(instances
			(project "polarfire-som"
				(path ""
					(reference "#PWR0262")
					(unit 1)
				)
			)
		)
	)
	(symbol
		(lib_id "antmicroCapacitors0402:C_1u_0402")
		(at 66.04 212.09 90)
		(unit 1)
		(exclude_from_sim no)
		(in_bom yes)
		(on_board yes)
		(dnp no)
		(fields_autoplaced yes)
		(property "Reference" "C114"
			(at 63.5 208.2735 90)
			(effects
				(font
					(size 1.27 1.27)
					(thickness 0.15)
				)
				(justify left)
			)
		)
		(property "Value" "C_1u_0402"
			(at 76.2 191.77 0)
			(effects
				(font
					(size 1.27 1.27)
					(thickness 0.15)
				)
				(justify left bottom)
				(hide yes)
			)
		)
		(property "Footprint" "antmicro-footprints:C_0402_1005Metric"
			(at 78.74 191.77 0)
			(effects
				(font
					(size 1.27 1.27)
					(thickness 0.15)
				)
				(justify left bottom)
				(hide yes)
			)
		)
		(property "Datasheet" "https://product.tdk.com/en/search/capacitor/ceramic/mlcc/info?part_no=C1005X6S1A105K050BC"
			(at 81.28 191.77 0)
			(effects
				(font
					(size 1.27 1.27)
					(thickness 0.15)
				)
				(justify left bottom)
				(hide yes)
			)
		)
		(property "Description" "SMD Multilayer Ceramic Capacitor, 1 µF, 10 V, 0402 [1005 Metric], ± 10%, X6S, C"
			(at 66.04 212.09 0)
			(effects
				(font
					(size 1.27 1.27)
				)
				(hide yes)
			)
		)
		(property "MPN" "C1005X6S1A105K050BC"
			(at 83.82 191.77 0)
			(effects
				(font
					(size 1.27 1.27)
					(thickness 0.15)
				)
				(justify left bottom)
				(hide yes)
			)
		)
		(property "Manufacturer" "TDK"
			(at 86.36 191.77 0)
			(effects
				(font
					(size 1.27 1.27)
					(thickness 0.15)
				)
				(justify left bottom)
				(hide yes)
			)
		)
		(property "License" "Apache-2.0"
			(at 88.9 191.77 0)
			(effects
				(font
					(size 1.27 1.27)
					(thickness 0.15)
				)
				(justify left bottom)
				(hide yes)
			)
		)
		(property "Author" "Antmicro"
			(at 91.44 191.77 0)
			(effects
				(font
					(size 1.27 1.27)
					(thickness 0.15)
				)
				(justify left bottom)
				(hide yes)
			)
		)
		(property "Val" "1u"
			(at 63.5 210.8135 90)
			(effects
				(font
					(size 1.27 1.27)
					(thickness 0.15)
				)
				(justify left)
			)
		)
		(property "Voltage" ""
			(at 93.98 191.77 0)
			(effects
				(font
					(size 1.27 1.27)
				)
				(justify left bottom)
				(hide yes)
			)
		)
		(property "Dielectric" ""
			(at 96.52 191.77 0)
			(effects
				(font
					(size 1.27 1.27)
				)
				(justify left bottom)
				(hide yes)
			)
		)
		(property "Public" ""
			(at 99.06 191.77 0)
			(effects
				(font
					(size 1.27 1.27)
				)
				(justify left bottom)
				(hide yes)
			)
		)
		(pin "1"
		)
		(pin "2"
		)
		(instances
			(project "polarfire-som"
				(path ""
					(reference "C114")
					(unit 1)
				)
			)
		)
	)
	(symbol
		(lib_id "antmicropower:+2V5")
		(at 99.06 224.79 0)
		(unit 1)
		(exclude_from_sim no)
		(in_bom yes)
		(on_board yes)
		(dnp no)
		(property "Reference" "#PWR0228"
			(at 99.06 228.6 0)
			(effects
				(font
					(size 1.27 1.27)
				)
				(hide yes)
			)
		)
		(property "Value" "+2V5"
			(at 99.06 220.98 0)
			(effects
				(font
					(size 1.27 1.27)
				)
			)
		)
		(property "Footprint" ""
			(at 99.06 224.79 0)
			(effects
				(font
					(size 1.27 1.27)
				)
				(hide yes)
			)
		)
		(property "Datasheet" ""
			(at 99.06 224.79 0)
			(effects
				(font
					(size 1.27 1.27)
				)
				(hide yes)
			)
		)
		(property "Description" ""
			(at 99.06 224.79 0)
			(effects
				(font
					(size 1.27 1.27)
				)
				(hide yes)
			)
		)
		(pin "1"
		)
		(instances
			(project "polarfire-som"
				(path ""
					(reference "#PWR0228")
					(unit 1)
				)
			)
		)
	)
	(symbol
		(lib_id "antmicroOscillators:Oscillator_25MHz_ESC_2016MV")
		(at 307.34 76.2 0)
		(unit 1)
		(exclude_from_sim no)
		(in_bom yes)
		(on_board yes)
		(dnp no)
		(fields_autoplaced yes)
		(property "Reference" "Y2"
			(at 316.865 66.04 0)
			(effects
				(font
					(size 1.27 1.27)
					(thickness 0.15)
				)
			)
		)
		(property "Value" "Oscillator_25MHz_ESC_2016MV"
			(at 332.74 88.9 0)
			(effects
				(font
					(size 1.27 1.27)
					(thickness 0.15)
				)
				(justify left bottom)
				(hide yes)
			)
		)
		(property "Footprint" "antmicro-footprints:Oscillator_SMD_ECS_2016MV_2x1.6x0.85mm"
			(at 332.74 91.44 0)
			(effects
				(font
					(size 1.27 1.27)
					(thickness 0.15)
				)
				(justify left bottom)
				(hide yes)
			)
		)
		(property "Datasheet" "https://ecsxtal.com/store/pdf/ECS-2016MV.pdf"
			(at 332.74 93.98 0)
			(effects
				(font
					(size 1.27 1.27)
					(thickness 0.15)
				)
				(justify left bottom)
				(hide yes)
			)
		)
		(property "Description" "Oscillator, 25 MHz, HCMOS, SMD, 2mm x 1.6mm, MultiVolt ECS-2016MV Series"
			(at 307.34 76.2 0)
			(effects
				(font
					(size 1.27 1.27)
				)
				(hide yes)
			)
		)
		(property "MPN" "ECS-2016MV-250-CN-TR"
			(at 316.865 68.58 0)
			(effects
				(font
					(size 1.27 1.27)
					(thickness 0.15)
				)
			)
		)
		(property "Manufacturer" "ECS Inc. International"
			(at 332.74 83.82 0)
			(effects
				(font
					(size 1.27 1.27)
					(thickness 0.15)
				)
				(justify left bottom)
				(hide yes)
			)
		)
		(property "Val" "25 MHz"
			(at 316.865 71.12 0)
			(effects
				(font
					(size 1.27 1.27)
					(thickness 0.15)
				)
			)
		)
		(property "Author" "Antmicro"
			(at 332.74 96.52 0)
			(effects
				(font
					(size 1.27 1.27)
					(thickness 0.15)
				)
				(justify left bottom)
				(hide yes)
			)
		)
		(property "License" "Apache-2.0"
			(at 332.74 99.06 0)
			(effects
				(font
					(size 1.27 1.27)
					(thickness 0.15)
				)
				(justify left bottom)
				(hide yes)
			)
		)
		(property "Public" ""
			(at 339.09 100.33 0)
			(effects
				(font
					(size 1.27 1.27)
				)
				(justify left bottom)
				(hide yes)
			)
		)
		(pin "1"
		)
		(pin "3"
		)
		(pin "4"
		)
		(pin "2"
		)
		(instances
			(project "polarfire-som"
				(path ""
					(reference "Y2")
					(unit 1)
				)
			)
		)
	)
	(symbol
		(lib_id "antmicroCapacitors0402:C_100n_0402")
		(at 168.91 96.52 180)
		(unit 1)
		(exclude_from_sim no)
		(in_bom yes)
		(on_board yes)
		(dnp yes)
		(property "Reference" "C258"
			(at 161.29 95.25 0)
			(effects
				(font
					(size 1.27 1.27)
					(thickness 0.15)
				)
				(justify left)
			)
		)
		(property "Value" "C_100n_0402"
			(at 148.59 86.36 0)
			(effects
				(font
					(size 1.27 1.27)
					(thickness 0.15)
				)
				(justify left bottom)
				(hide yes)
			)
		)
		(property "Footprint" "antmicro-footprints:C_0402_1005Metric"
			(at 148.59 83.82 0)
			(effects
				(font
					(size 1.27 1.27)
					(thickness 0.15)
				)
				(justify left bottom)
				(hide yes)
			)
		)
		(property "Datasheet" "https://www.murata.com/products/productdetail?partno=GRM155R61H104KE14%23"
			(at 148.59 81.28 0)
			(effects
				(font
					(size 1.27 1.27)
					(thickness 0.15)
				)
				(justify left bottom)
				(hide yes)
			)
		)
		(property "Description" "SMD Multilayer Ceramic Capacitor, 0.1 µF, 50 V, 0402 [1005 Metric], ± 10%, X5R, GRM Series"
			(at 168.91 96.52 0)
			(effects
				(font
					(size 1.27 1.27)
				)
				(hide yes)
			)
		)
		(property "MPN" "GRM155R61H104KE14D"
			(at 148.59 78.74 0)
			(effects
				(font
					(size 1.27 1.27)
					(thickness 0.15)
				)
				(justify left bottom)
				(hide yes)
			)
		)
		(property "Manufacturer" "Murata"
			(at 148.59 76.2 0)
			(effects
				(font
					(size 1.27 1.27)
					(thickness 0.15)
				)
				(justify left bottom)
				(hide yes)
			)
		)
		(property "License" "Apache-2.0"
			(at 148.59 73.66 0)
			(effects
				(font
					(size 1.27 1.27)
					(thickness 0.15)
				)
				(justify left bottom)
				(hide yes)
			)
		)
		(property "Author" "Antmicro"
			(at 148.59 71.12 0)
			(effects
				(font
					(size 1.27 1.27)
					(thickness 0.15)
				)
				(justify left bottom)
				(hide yes)
			)
		)
		(property "Val" "100n"
			(at 176.53 96.52 0)
			(effects
				(font
					(size 1.27 1.27)
					(thickness 0.15)
				)
				(justify left top)
			)
		)
		(property "Voltage" "50V"
			(at 148.59 68.58 0)
			(effects
				(font
					(size 1.27 1.27)
				)
				(justify left bottom)
				(hide yes)
			)
		)
		(property "Dielectric" "X5R"
			(at 148.59 66.04 0)
			(effects
				(font
					(size 1.27 1.27)
				)
				(justify left bottom)
				(hide yes)
			)
		)
		(property "DNP" "DNP"
			(at 171.45 96.52 0)
			(effects
				(font
					(size 1.27 1.27)
					(bold yes)
				)
				(justify left top)
				(hide yes)
			)
		)
		(property "Public" ""
			(at 148.59 63.5 0)
			(effects
				(font
					(size 1.27 1.27)
				)
				(justify left bottom)
				(hide yes)
			)
		)
		(pin "1"
		)
		(pin "2"
		)
		(instances
			(project "polarfire-som"
				(path ""
					(reference "C258")
					(unit 1)
				)
			)
		)
	)
	(symbol
		(lib_id "antmicropower:GND")
		(at 72.39 213.36 0)
		(unit 1)
		(exclude_from_sim no)
		(in_bom yes)
		(on_board yes)
		(dnp no)
		(property "Reference" "#PWR0222"
			(at 81.28 215.9 0)
			(effects
				(font
					(size 1.27 1.27)
					(thickness 0.15)
				)
				(justify left bottom)
				(hide yes)
			)
		)
		(property "Value" "GND"
			(at 72.39 217.17 0)
			(effects
				(font
					(size 1.27 1.27)
					(thickness 0.15)
				)
			)
		)
		(property "Footprint" ""
			(at 81.28 220.98 0)
			(effects
				(font
					(size 1.27 1.27)
					(thickness 0.15)
				)
				(justify left bottom)
				(hide yes)
			)
		)
		(property "Datasheet" ""
			(at 81.28 226.06 0)
			(effects
				(font
					(size 1.27 1.27)
					(thickness 0.15)
				)
				(justify left bottom)
				(hide yes)
			)
		)
		(property "Description" ""
			(at 72.39 213.36 0)
			(effects
				(font
					(size 1.27 1.27)
				)
				(hide yes)
			)
		)
		(property "Author" "Antmicro"
			(at 81.28 220.98 0)
			(effects
				(font
					(size 1.27 1.27)
					(thickness 0.15)
				)
				(justify left bottom)
				(hide yes)
			)
		)
		(property "License" "Apache-2.0"
			(at 81.28 223.52 0)
			(effects
				(font
					(size 1.27 1.27)
					(thickness 0.15)
				)
				(justify left bottom)
				(hide yes)
			)
		)
		(pin "1"
		)
		(instances
			(project "polarfire-som"
				(path ""
					(reference "#PWR0222")
					(unit 1)
				)
			)
		)
	)
	(symbol
		(lib_id "antmicroCapacitors0402:C_1u_0402")
		(at 99.06 212.09 270)
		(mirror x)
		(unit 1)
		(exclude_from_sim no)
		(in_bom yes)
		(on_board yes)
		(dnp no)
		(fields_autoplaced yes)
		(property "Reference" "C193"
			(at 96.52 208.2735 90)
			(effects
				(font
					(size 1.27 1.27)
					(thickness 0.15)
				)
				(justify right)
			)
		)
		(property "Value" "C_1u_0402"
			(at 88.9 191.77 0)
			(effects
				(font
					(size 1.27 1.27)
					(thickness 0.15)
				)
				(justify left bottom)
				(hide yes)
			)
		)
		(property "Footprint" "antmicro-footprints:C_0402_1005Metric"
			(at 86.36 191.77 0)
			(effects
				(font
					(size 1.27 1.27)
					(thickness 0.15)
				)
				(justify left bottom)
				(hide yes)
			)
		)
		(property "Datasheet" "https://product.tdk.com/en/search/capacitor/ceramic/mlcc/info?part_no=C1005X6S1A105K050BC"
			(at 83.82 191.77 0)
			(effects
				(font
					(size 1.27 1.27)
					(thickness 0.15)
				)
				(justify left bottom)
				(hide yes)
			)
		)
		(property "Description" "SMD Multilayer Ceramic Capacitor, 1 µF, 10 V, 0402 [1005 Metric], ± 10%, X6S, C"
			(at 99.06 212.09 0)
			(effects
				(font
					(size 1.27 1.27)
				)
				(hide yes)
			)
		)
		(property "MPN" "C1005X6S1A105K050BC"
			(at 81.28 191.77 0)
			(effects
				(font
					(size 1.27 1.27)
					(thickness 0.15)
				)
				(justify left bottom)
				(hide yes)
			)
		)
		(property "Manufacturer" "TDK"
			(at 78.74 191.77 0)
			(effects
				(font
					(size 1.27 1.27)
					(thickness 0.15)
				)
				(justify left bottom)
				(hide yes)
			)
		)
		(property "License" "Apache-2.0"
			(at 76.2 191.77 0)
			(effects
				(font
					(size 1.27 1.27)
					(thickness 0.15)
				)
				(justify left bottom)
				(hide yes)
			)
		)
		(property "Author" "Antmicro"
			(at 73.66 191.77 0)
			(effects
				(font
					(size 1.27 1.27)
					(thickness 0.15)
				)
				(justify left bottom)
				(hide yes)
			)
		)
		(property "Val" "1u"
			(at 96.52 210.8135 90)
			(effects
				(font
					(size 1.27 1.27)
					(thickness 0.15)
				)
				(justify right)
			)
		)
		(property "Voltage" ""
			(at 71.12 191.77 0)
			(effects
				(font
					(size 1.27 1.27)
				)
				(justify left bottom)
				(hide yes)
			)
		)
		(property "Dielectric" ""
			(at 68.58 191.77 0)
			(effects
				(font
					(size 1.27 1.27)
				)
				(justify left bottom)
				(hide yes)
			)
		)
		(property "Public" ""
			(at 66.04 191.77 0)
			(effects
				(font
					(size 1.27 1.27)
				)
				(justify left bottom)
				(hide yes)
			)
		)
		(pin "1"
		)
		(pin "2"
		)
		(instances
			(project "polarfire-som"
				(path ""
					(reference "C193")
					(unit 1)
				)
			)
		)
	)
	(symbol
		(lib_id "antmicropower:GND")
		(at 105.41 194.31 0)
		(unit 1)
		(exclude_from_sim no)
		(in_bom yes)
		(on_board yes)
		(dnp no)
		(property "Reference" "#PWR0229"
			(at 114.3 196.85 0)
			(effects
				(font
					(size 1.27 1.27)
					(thickness 0.15)
				)
				(justify left bottom)
				(hide yes)
			)
		)
		(property "Value" "GND"
			(at 105.41 198.12 0)
			(effects
				(font
					(size 1.27 1.27)
					(thickness 0.15)
				)
			)
		)
		(property "Footprint" ""
			(at 114.3 201.93 0)
			(effects
				(font
					(size 1.27 1.27)
					(thickness 0.15)
				)
				(justify left bottom)
				(hide yes)
			)
		)
		(property "Datasheet" ""
			(at 114.3 207.01 0)
			(effects
				(font
					(size 1.27 1.27)
					(thickness 0.15)
				)
				(justify left bottom)
				(hide yes)
			)
		)
		(property "Description" ""
			(at 105.41 194.31 0)
			(effects
				(font
					(size 1.27 1.27)
				)
				(hide yes)
			)
		)
		(property "Author" "Antmicro"
			(at 114.3 201.93 0)
			(effects
				(font
					(size 1.27 1.27)
					(thickness 0.15)
				)
				(justify left bottom)
				(hide yes)
			)
		)
		(property "License" "Apache-2.0"
			(at 114.3 204.47 0)
			(effects
				(font
					(size 1.27 1.27)
					(thickness 0.15)
				)
				(justify left bottom)
				(hide yes)
			)
		)
		(pin "1"
		)
		(instances
			(project "polarfire-som"
				(path ""
					(reference "#PWR0229")
					(unit 1)
				)
			)
		)
	)
	(symbol
		(lib_id "antmicroCapacitors0402:C_100n_0402")
		(at 72.39 231.14 90)
		(unit 1)
		(exclude_from_sim no)
		(in_bom yes)
		(on_board yes)
		(dnp no)
		(property "Reference" "C190"
			(at 74.93 227.3235 90)
			(effects
				(font
					(size 1.27 1.27)
					(thickness 0.15)
				)
				(justify right)
			)
		)
		(property "Value" "C_100n_0402"
			(at 82.55 210.82 0)
			(effects
				(font
					(size 1.27 1.27)
					(thickness 0.15)
				)
				(justify left bottom)
				(hide yes)
			)
		)
		(property "Footprint" "antmicro-footprints:C_0402_1005Metric"
			(at 85.09 210.82 0)
			(effects
				(font
					(size 1.27 1.27)
					(thickness 0.15)
				)
				(justify left bottom)
				(hide yes)
			)
		)
		(property "Datasheet" "https://www.murata.com/products/productdetail?partno=GRM155R61H104KE14%23"
			(at 87.63 210.82 0)
			(effects
				(font
					(size 1.27 1.27)
					(thickness 0.15)
				)
				(justify left bottom)
				(hide yes)
			)
		)
		(property "Description" "SMD Multilayer Ceramic Capacitor, 0.1 µF, 50 V, 0402 [1005 Metric], ± 10%, X5R, GRM Series"
			(at 72.39 231.14 0)
			(effects
				(font
					(size 1.27 1.27)
				)
				(hide yes)
			)
		)
		(property "MPN" "GRM155R61H104KE14D"
			(at 90.17 210.82 0)
			(effects
				(font
					(size 1.27 1.27)
					(thickness 0.15)
				)
				(justify left bottom)
				(hide yes)
			)
		)
		(property "Manufacturer" "Murata"
			(at 92.71 210.82 0)
			(effects
				(font
					(size 1.27 1.27)
					(thickness 0.15)
				)
				(justify left bottom)
				(hide yes)
			)
		)
		(property "License" "Apache-2.0"
			(at 95.25 210.82 0)
			(effects
				(font
					(size 1.27 1.27)
					(thickness 0.15)
				)
				(justify left bottom)
				(hide yes)
			)
		)
		(property "Author" "Antmicro"
			(at 97.79 210.82 0)
			(effects
				(font
					(size 1.27 1.27)
					(thickness 0.15)
				)
				(justify left bottom)
				(hide yes)
			)
		)
		(property "Val" "100n"
			(at 80.01 229.235 90)
			(effects
				(font
					(size 1.27 1.27)
					(thickness 0.15)
				)
				(justify left bottom)
			)
		)
		(property "Voltage" "50V"
			(at 100.33 210.82 0)
			(effects
				(font
					(size 1.27 1.27)
				)
				(justify left bottom)
				(hide yes)
			)
		)
		(property "Dielectric" "X5R"
			(at 102.87 210.82 0)
			(effects
				(font
					(size 1.27 1.27)
				)
				(justify left bottom)
				(hide yes)
			)
		)
		(property "Public" ""
			(at 105.41 210.82 0)
			(effects
				(font
					(size 1.27 1.27)
				)
				(justify left bottom)
				(hide yes)
			)
		)
		(pin "1"
		)
		(pin "2"
		)
		(instances
			(project "polarfire-som"
				(path ""
					(reference "C190")
					(unit 1)
				)
			)
		)
	)
	(symbol
		(lib_id "antmicroResistors0402:R_1k5_0402")
		(at 74.93 124.46 0)
		(unit 1)
		(exclude_from_sim no)
		(in_bom yes)
		(on_board yes)
		(dnp no)
		(property "Reference" "R137"
			(at 72.39 123.19 0)
			(effects
				(font
					(size 1.27 1.27)
					(thickness 0.15)
				)
			)
		)
		(property "Value" "R_1k5_0402"
			(at 95.25 137.16 0)
			(effects
				(font
					(size 1.27 1.27)
					(thickness 0.15)
				)
				(justify left bottom)
				(hide yes)
			)
		)
		(property "Footprint" "antmicro-footprints:R_0402_1005Metric"
			(at 95.25 139.7 0)
			(effects
				(font
					(size 1.27 1.27)
					(thickness 0.15)
				)
				(justify left bottom)
				(hide yes)
			)
		)
		(property "Datasheet" "https://www.bourns.com/docs/product-datasheets/cr.pdf"
			(at 95.25 142.24 0)
			(effects
				(font
					(size 1.27 1.27)
					(thickness 0.15)
				)
				(justify left bottom)
				(hide yes)
			)
		)
		(property "Description" "SMD Chip Resistor, 1.5 kohm, ± 1%, 62.5 mW, 0402 [1005 Metric], Thick Film, General Purpose"
			(at 74.93 124.46 0)
			(effects
				(font
					(size 1.27 1.27)
				)
				(hide yes)
			)
		)
		(property "MPN" "CR0402-FX-1501GLF"
			(at 95.25 144.78 0)
			(effects
				(font
					(size 1.27 1.27)
					(thickness 0.15)
				)
				(justify left bottom)
				(hide yes)
			)
		)
		(property "Manufacturer" "Bourns"
			(at 95.25 147.32 0)
			(effects
				(font
					(size 1.27 1.27)
					(thickness 0.15)
				)
				(justify left bottom)
				(hide yes)
			)
		)
		(property "License" "Apache-2.0"
			(at 95.25 149.86 0)
			(effects
				(font
					(size 1.27 1.27)
					(thickness 0.15)
				)
				(justify left bottom)
				(hide yes)
			)
		)
		(property "Author" "Antmicro"
			(at 95.25 152.4 0)
			(effects
				(font
					(size 1.27 1.27)
					(thickness 0.15)
				)
				(justify left bottom)
				(hide yes)
			)
		)
		(property "Val" "1k5"
			(at 81.915 123.19 0)
			(effects
				(font
					(size 1.27 1.27)
					(thickness 0.15)
				)
			)
		)
		(property "Tolerance" "1%"
			(at 95.25 134.62 0)
			(effects
				(font
					(size 1.27 1.27)
				)
				(justify left bottom)
				(hide yes)
			)
		)
		(property "Public" ""
			(at 95.25 154.94 0)
			(effects
				(font
					(size 1.27 1.27)
				)
				(justify left bottom)
				(hide yes)
			)
		)
		(pin "1"
		)
		(pin "2"
		)
		(instances
			(project "polarfire-som"
				(path ""
					(reference "R137")
					(unit 1)
				)
			)
		)
	)
	(symbol
		(lib_id "antmicropower:+1V05")
		(at 130.81 186.69 0)
		(unit 1)
		(exclude_from_sim no)
		(in_bom yes)
		(on_board yes)
		(dnp no)
		(property "Reference" "#PWR0234"
			(at 130.81 190.5 0)
			(effects
				(font
					(size 1.27 1.27)
				)
				(hide yes)
			)
		)
		(property "Value" "+1V05"
			(at 130.81 182.88 0)
			(effects
				(font
					(size 1.27 1.27)
				)
			)
		)
		(property "Footprint" ""
			(at 130.81 186.69 0)
			(effects
				(font
					(size 1.27 1.27)
				)
				(hide yes)
			)
		)
		(property "Datasheet" ""
			(at 130.81 186.69 0)
			(effects
				(font
					(size 1.27 1.27)
				)
				(hide yes)
			)
		)
		(property "Description" ""
			(at 130.81 186.69 0)
			(effects
				(font
					(size 1.27 1.27)
				)
				(hide yes)
			)
		)
		(pin "1"
		)
		(instances
			(project "polarfire-som"
				(path ""
					(reference "#PWR0234")
					(unit 1)
				)
			)
		)
	)
	(symbol
		(lib_id "antmicropower:+3V3")
		(at 67.31 123.19 0)
		(unit 1)
		(exclude_from_sim no)
		(in_bom yes)
		(on_board yes)
		(dnp no)
		(fields_autoplaced yes)
		(property "Reference" "#PWR0256"
			(at 82.55 125.73 0)
			(effects
				(font
					(size 1.27 1.27)
					(thickness 0.15)
				)
				(justify left bottom)
				(hide yes)
			)
		)
		(property "Value" "+3V3"
			(at 67.31 118.11 0)
			(effects
				(font
					(size 1.27 1.27)
					(thickness 0.15)
				)
			)
		)
		(property "Footprint" ""
			(at 82.55 130.81 0)
			(effects
				(font
					(size 1.27 1.27)
					(thickness 0.15)
				)
				(justify left bottom)
				(hide yes)
			)
		)
		(property "Datasheet" ""
			(at 82.55 133.35 0)
			(effects
				(font
					(size 1.27 1.27)
					(thickness 0.15)
				)
				(justify left bottom)
				(hide yes)
			)
		)
		(property "Description" ""
			(at 67.31 123.19 0)
			(effects
				(font
					(size 1.27 1.27)
				)
				(hide yes)
			)
		)
		(property "Author" "Antmicro"
			(at 82.55 130.81 0)
			(effects
				(font
					(size 1.27 1.27)
					(thickness 0.15)
				)
				(justify left bottom)
				(hide yes)
			)
		)
		(property "License" "Apache-2.0"
			(at 82.55 133.35 0)
			(effects
				(font
					(size 1.27 1.27)
					(thickness 0.15)
				)
				(justify left bottom)
				(hide yes)
			)
		)
		(pin "1"
		)
		(instances
			(project "polarfire-som"
				(path ""
					(reference "#PWR0256")
					(unit 1)
				)
			)
		)
	)
	(symbol
		(lib_id "antmicropower:+1V05")
		(at 130.81 224.79 0)
		(unit 1)
		(exclude_from_sim no)
		(in_bom yes)
		(on_board yes)
		(dnp no)
		(property "Reference" "#PWR0237"
			(at 130.81 228.6 0)
			(effects
				(font
					(size 1.27 1.27)
				)
				(hide yes)
			)
		)
		(property "Value" "+1V05"
			(at 130.81 220.98 0)
			(effects
				(font
					(size 1.27 1.27)
				)
			)
		)
		(property "Footprint" ""
			(at 130.81 224.79 0)
			(effects
				(font
					(size 1.27 1.27)
				)
				(hide yes)
			)
		)
		(property "Datasheet" ""
			(at 130.81 224.79 0)
			(effects
				(font
					(size 1.27 1.27)
				)
				(hide yes)
			)
		)
		(property "Description" ""
			(at 130.81 224.79 0)
			(effects
				(font
					(size 1.27 1.27)
				)
				(hide yes)
			)
		)
		(pin "1"
		)
		(instances
			(project "polarfire-som"
				(path ""
					(reference "#PWR0237")
					(unit 1)
				)
			)
		)
	)
	(symbol
		(lib_id "antmicroResistors0402:R_2k2_0402")
		(at 330.2 203.2 90)
		(unit 1)
		(exclude_from_sim no)
		(in_bom yes)
		(on_board yes)
		(dnp no)
		(fields_autoplaced yes)
		(property "Reference" "R96"
			(at 332.74 199.39 90)
			(effects
				(font
					(size 1.27 1.27)
					(thickness 0.15)
				)
				(justify right)
			)
		)
		(property "Value" "R_2k2_0402"
			(at 342.9 182.88 0)
			(effects
				(font
					(size 1.27 1.27)
					(thickness 0.15)
				)
				(justify left bottom)
				(hide yes)
			)
		)
		(property "Footprint" "antmicro-footprints:R_0402_1005Metric"
			(at 345.44 182.88 0)
			(effects
				(font
					(size 1.27 1.27)
					(thickness 0.15)
				)
				(justify left bottom)
				(hide yes)
			)
		)
		(property "Datasheet" "https://www.bourns.com/docs/product-datasheets/cr.pdf"
			(at 347.98 182.88 0)
			(effects
				(font
					(size 1.27 1.27)
					(thickness 0.15)
				)
				(justify left bottom)
				(hide yes)
			)
		)
		(property "Description" "SMD Chip Resistor, 2.2 kohm, ± 1%, 62.5 mW, 0402 [1005 Metric], Thick Film, General Purpose"
			(at 330.2 203.2 0)
			(effects
				(font
					(size 1.27 1.27)
				)
				(hide yes)
			)
		)
		(property "MPN" "CR0402-FX-2201GLF"
			(at 350.52 182.88 0)
			(effects
				(font
					(size 1.27 1.27)
					(thickness 0.15)
				)
				(justify left bottom)
				(hide yes)
			)
		)
		(property "Manufacturer" "Bourns"
			(at 353.06 182.88 0)
			(effects
				(font
					(size 1.27 1.27)
					(thickness 0.15)
				)
				(justify left bottom)
				(hide yes)
			)
		)
		(property "License" "Apache-2.0"
			(at 355.6 182.88 0)
			(effects
				(font
					(size 1.27 1.27)
					(thickness 0.15)
				)
				(justify left bottom)
				(hide yes)
			)
		)
		(property "Author" "Antmicro"
			(at 358.14 182.88 0)
			(effects
				(font
					(size 1.27 1.27)
					(thickness 0.15)
				)
				(justify left bottom)
				(hide yes)
			)
		)
		(property "Val" "2k2"
			(at 332.74 201.93 90)
			(effects
				(font
					(size 1.27 1.27)
					(thickness 0.15)
				)
				(justify right)
			)
		)
		(property "Tolerance" "1%"
			(at 340.36 182.88 0)
			(effects
				(font
					(size 1.27 1.27)
				)
				(justify left bottom)
				(hide yes)
			)
		)
		(property "Public" ""
			(at 360.68 182.88 0)
			(effects
				(font
					(size 1.27 1.27)
				)
				(justify left bottom)
				(hide yes)
			)
		)
		(pin "1"
		)
		(pin "2"
		)
		(instances
			(project "polarfire-som"
				(path ""
					(reference "R96")
					(unit 1)
				)
			)
		)
	)
	(symbol
		(lib_id "antmicropower:+3V3")
		(at 66.04 186.69 0)
		(unit 1)
		(exclude_from_sim no)
		(in_bom yes)
		(on_board yes)
		(dnp no)
		(fields_autoplaced yes)
		(property "Reference" "#PWR0296"
			(at 81.28 189.23 0)
			(effects
				(font
					(size 1.27 1.27)
					(thickness 0.15)
				)
				(justify left bottom)
				(hide yes)
			)
		)
		(property "Value" "+3V3"
			(at 66.04 181.61 0)
			(effects
				(font
					(size 1.27 1.27)
					(thickness 0.15)
				)
			)
		)
		(property "Footprint" ""
			(at 81.28 194.31 0)
			(effects
				(font
					(size 1.27 1.27)
					(thickness 0.15)
				)
				(justify left bottom)
				(hide yes)
			)
		)
		(property "Datasheet" ""
			(at 81.28 196.85 0)
			(effects
				(font
					(size 1.27 1.27)
					(thickness 0.15)
				)
				(justify left bottom)
				(hide yes)
			)
		)
		(property "Description" ""
			(at 66.04 186.69 0)
			(effects
				(font
					(size 1.27 1.27)
				)
				(hide yes)
			)
		)
		(property "Author" "Antmicro"
			(at 81.28 194.31 0)
			(effects
				(font
					(size 1.27 1.27)
					(thickness 0.15)
				)
				(justify left bottom)
				(hide yes)
			)
		)
		(property "License" "Apache-2.0"
			(at 81.28 196.85 0)
			(effects
				(font
					(size 1.27 1.27)
					(thickness 0.15)
				)
				(justify left bottom)
				(hide yes)
			)
		)
		(pin "1"
		)
		(instances
			(project "polarfire-som"
				(path ""
					(reference "#PWR0296")
					(unit 1)
				)
			)
		)
	)
	(symbol
		(lib_id "antmicroResistors0402:R_2k2_0402")
		(at 313.69 203.2 90)
		(unit 1)
		(exclude_from_sim no)
		(in_bom yes)
		(on_board yes)
		(dnp no)
		(property "Reference" "R103"
			(at 317.5 199.39 90)
			(effects
				(font
					(size 1.27 1.27)
					(thickness 0.15)
				)
			)
		)
		(property "Value" "R_2k2_0402"
			(at 326.39 182.88 0)
			(effects
				(font
					(size 1.27 1.27)
					(thickness 0.15)
				)
				(justify left bottom)
				(hide yes)
			)
		)
		(property "Footprint" "antmicro-footprints:R_0402_1005Metric"
			(at 328.93 182.88 0)
			(effects
				(font
					(size 1.27 1.27)
					(thickness 0.15)
				)
				(justify left bottom)
				(hide yes)
			)
		)
		(property "Datasheet" "https://www.bourns.com/docs/product-datasheets/cr.pdf"
			(at 331.47 182.88 0)
			(effects
				(font
					(size 1.27 1.27)
					(thickness 0.15)
				)
				(justify left bottom)
				(hide yes)
			)
		)
		(property "Description" "SMD Chip Resistor, 2.2 kohm, ± 1%, 62.5 mW, 0402 [1005 Metric], Thick Film, General Purpose"
			(at 313.69 203.2 0)
			(effects
				(font
					(size 1.27 1.27)
				)
				(hide yes)
			)
		)
		(property "MPN" "CR0402-FX-2201GLF"
			(at 334.01 182.88 0)
			(effects
				(font
					(size 1.27 1.27)
					(thickness 0.15)
				)
				(justify left bottom)
				(hide yes)
			)
		)
		(property "Manufacturer" "Bourns"
			(at 336.55 182.88 0)
			(effects
				(font
					(size 1.27 1.27)
					(thickness 0.15)
				)
				(justify left bottom)
				(hide yes)
			)
		)
		(property "License" "Apache-2.0"
			(at 339.09 182.88 0)
			(effects
				(font
					(size 1.27 1.27)
					(thickness 0.15)
				)
				(justify left bottom)
				(hide yes)
			)
		)
		(property "Author" "Antmicro"
			(at 341.63 182.88 0)
			(effects
				(font
					(size 1.27 1.27)
					(thickness 0.15)
				)
				(justify left bottom)
				(hide yes)
			)
		)
		(property "Val" "2k2"
			(at 317.5 201.93 90)
			(effects
				(font
					(size 1.27 1.27)
					(thickness 0.15)
				)
			)
		)
		(property "Tolerance" "1%"
			(at 323.85 182.88 0)
			(effects
				(font
					(size 1.27 1.27)
				)
				(justify left bottom)
				(hide yes)
			)
		)
		(property "Public" ""
			(at 344.17 182.88 0)
			(effects
				(font
					(size 1.27 1.27)
				)
				(justify left bottom)
				(hide yes)
			)
		)
		(pin "1"
		)
		(pin "2"
		)
		(instances
			(project "polarfire-som"
				(path ""
					(reference "R103")
					(unit 1)
				)
			)
		)
	)
	(symbol
		(lib_id "antmicropower:GND")
		(at 130.81 232.41 0)
		(unit 1)
		(exclude_from_sim no)
		(in_bom yes)
		(on_board yes)
		(dnp no)
		(property "Reference" "#PWR0238"
			(at 139.7 234.95 0)
			(effects
				(font
					(size 1.27 1.27)
					(thickness 0.15)
				)
				(justify left bottom)
				(hide yes)
			)
		)
		(property "Value" "GND"
			(at 130.81 236.22 0)
			(effects
				(font
					(size 1.27 1.27)
					(thickness 0.15)
				)
			)
		)
		(property "Footprint" ""
			(at 139.7 240.03 0)
			(effects
				(font
					(size 1.27 1.27)
					(thickness 0.15)
				)
				(justify left bottom)
				(hide yes)
			)
		)
		(property "Datasheet" ""
			(at 139.7 245.11 0)
			(effects
				(font
					(size 1.27 1.27)
					(thickness 0.15)
				)
				(justify left bottom)
				(hide yes)
			)
		)
		(property "Description" ""
			(at 130.81 232.41 0)
			(effects
				(font
					(size 1.27 1.27)
				)
				(hide yes)
			)
		)
		(property "Author" "Antmicro"
			(at 139.7 240.03 0)
			(effects
				(font
					(size 1.27 1.27)
					(thickness 0.15)
				)
				(justify left bottom)
				(hide yes)
			)
		)
		(property "License" "Apache-2.0"
			(at 139.7 242.57 0)
			(effects
				(font
					(size 1.27 1.27)
					(thickness 0.15)
				)
				(justify left bottom)
				(hide yes)
			)
		)
		(pin "1"
		)
		(instances
			(project "polarfire-som"
				(path ""
					(reference "#PWR0238")
					(unit 1)
				)
			)
		)
	)
	(symbol
		(lib_id "antmicroCapacitors0402:C_10n_0402")
		(at 137.16 193.04 90)
		(unit 1)
		(exclude_from_sim no)
		(in_bom yes)
		(on_board yes)
		(dnp no)
		(fields_autoplaced yes)
		(property "Reference" "C255"
			(at 139.7 189.2235 90)
			(effects
				(font
					(size 1.27 1.27)
					(thickness 0.15)
				)
				(justify right)
			)
		)
		(property "Value" "C_10n_0402"
			(at 147.32 172.72 0)
			(effects
				(font
					(size 1.27 1.27)
					(thickness 0.15)
				)
				(justify left bottom)
				(hide yes)
			)
		)
		(property "Footprint" "antmicro-footprints:C_0402_1005Metric"
			(at 149.86 172.72 0)
			(effects
				(font
					(size 1.27 1.27)
					(thickness 0.15)
				)
				(justify left bottom)
				(hide yes)
			)
		)
		(property "Datasheet" "https://www.murata.com/products/productdetail?partno=GRM155R71H103KA88%23"
			(at 152.4 172.72 0)
			(effects
				(font
					(size 1.27 1.27)
					(thickness 0.15)
				)
				(justify left bottom)
				(hide yes)
			)
		)
		(property "Description" "SMD Multilayer Ceramic Capacitor, 10000 pF, 50 V, 0402 [1005 Metric], ± 10%, X7R, GRM Series"
			(at 137.16 193.04 0)
			(effects
				(font
					(size 1.27 1.27)
				)
				(hide yes)
			)
		)
		(property "MPN" "GRM155R71H103KA88D"
			(at 154.94 172.72 0)
			(effects
				(font
					(size 1.27 1.27)
					(thickness 0.15)
				)
				(justify left bottom)
				(hide yes)
			)
		)
		(property "Manufacturer" "Murata"
			(at 157.48 172.72 0)
			(effects
				(font
					(size 1.27 1.27)
					(thickness 0.15)
				)
				(justify left bottom)
				(hide yes)
			)
		)
		(property "License" "Apache-2.0"
			(at 160.02 172.72 0)
			(effects
				(font
					(size 1.27 1.27)
					(thickness 0.15)
				)
				(justify left bottom)
				(hide yes)
			)
		)
		(property "Author" "Antmicro"
			(at 162.56 172.72 0)
			(effects
				(font
					(size 1.27 1.27)
					(thickness 0.15)
				)
				(justify left bottom)
				(hide yes)
			)
		)
		(property "Val" "10n"
			(at 139.7 191.7635 90)
			(effects
				(font
					(size 1.27 1.27)
					(thickness 0.15)
				)
				(justify right)
			)
		)
		(property "Voltage" "50V"
			(at 165.1 172.72 0)
			(effects
				(font
					(size 1.27 1.27)
				)
				(justify left bottom)
				(hide yes)
			)
		)
		(property "Dielectric" "X7R"
			(at 167.64 172.72 0)
			(effects
				(font
					(size 1.27 1.27)
				)
				(justify left bottom)
				(hide yes)
			)
		)
		(property "Public" ""
			(at 170.18 172.72 0)
			(effects
				(font
					(size 1.27 1.27)
				)
				(justify left bottom)
				(hide yes)
			)
		)
		(pin "1"
		)
		(pin "2"
		)
		(instances
			(project "polarfire-som"
				(path ""
					(reference "C255")
					(unit 1)
				)
			)
		)
	)
	(symbol
		(lib_id "antmicroCapacitors0402:C_100n_0402")
		(at 168.91 101.6 180)
		(unit 1)
		(exclude_from_sim no)
		(in_bom yes)
		(on_board yes)
		(dnp no)
		(property "Reference" "C259"
			(at 161.29 100.33 0)
			(effects
				(font
					(size 1.27 1.27)
					(thickness 0.15)
				)
				(justify left)
			)
		)
		(property "Value" "C_100n_0402"
			(at 148.59 91.44 0)
			(effects
				(font
					(size 1.27 1.27)
					(thickness 0.15)
				)
				(justify left bottom)
				(hide yes)
			)
		)
		(property "Footprint" "antmicro-footprints:C_0402_1005Metric"
			(at 148.59 88.9 0)
			(effects
				(font
					(size 1.27 1.27)
					(thickness 0.15)
				)
				(justify left bottom)
				(hide yes)
			)
		)
		(property "Datasheet" "https://www.murata.com/products/productdetail?partno=GRM155R61H104KE14%23"
			(at 148.59 86.36 0)
			(effects
				(font
					(size 1.27 1.27)
					(thickness 0.15)
				)
				(justify left bottom)
				(hide yes)
			)
		)
		(property "Description" "SMD Multilayer Ceramic Capacitor, 0.1 µF, 50 V, 0402 [1005 Metric], ± 10%, X5R, GRM Series"
			(at 168.91 101.6 0)
			(effects
				(font
					(size 1.27 1.27)
				)
				(hide yes)
			)
		)
		(property "MPN" "GRM155R61H104KE14D"
			(at 148.59 83.82 0)
			(effects
				(font
					(size 1.27 1.27)
					(thickness 0.15)
				)
				(justify left bottom)
				(hide yes)
			)
		)
		(property "Manufacturer" "Murata"
			(at 148.59 81.28 0)
			(effects
				(font
					(size 1.27 1.27)
					(thickness 0.15)
				)
				(justify left bottom)
				(hide yes)
			)
		)
		(property "License" "Apache-2.0"
			(at 148.59 78.74 0)
			(effects
				(font
					(size 1.27 1.27)
					(thickness 0.15)
				)
				(justify left bottom)
				(hide yes)
			)
		)
		(property "Author" "Antmicro"
			(at 148.59 76.2 0)
			(effects
				(font
					(size 1.27 1.27)
					(thickness 0.15)
				)
				(justify left bottom)
				(hide yes)
			)
		)
		(property "Val" "100n"
			(at 173.99 101.6 0)
			(effects
				(font
					(size 1.27 1.27)
					(thickness 0.15)
				)
				(justify left top)
			)
		)
		(property "Voltage" "50V"
			(at 148.59 73.66 0)
			(effects
				(font
					(size 1.27 1.27)
				)
				(justify left bottom)
				(hide yes)
			)
		)
		(property "Dielectric" "X5R"
			(at 148.59 71.12 0)
			(effects
				(font
					(size 1.27 1.27)
				)
				(justify left bottom)
				(hide yes)
			)
		)
		(property "Public" ""
			(at 148.59 68.58 0)
			(effects
				(font
					(size 1.27 1.27)
				)
				(justify left bottom)
				(hide yes)
			)
		)
		(pin "1"
		)
		(pin "2"
		)
		(instances
			(project "polarfire-som"
				(path ""
					(reference "C259")
					(unit 1)
				)
			)
		)
	)
	(symbol
		(lib_id "antmicropower:+3V3")
		(at 140.97 57.15 0)
		(unit 1)
		(exclude_from_sim no)
		(in_bom yes)
		(on_board yes)
		(dnp no)
		(fields_autoplaced yes)
		(property "Reference" "#PWR0258"
			(at 156.21 59.69 0)
			(effects
				(font
					(size 1.27 1.27)
					(thickness 0.15)
				)
				(justify left bottom)
				(hide yes)
			)
		)
		(property "Value" "+3V3"
			(at 140.97 52.07 0)
			(effects
				(font
					(size 1.27 1.27)
					(thickness 0.15)
				)
			)
		)
		(property "Footprint" ""
			(at 156.21 64.77 0)
			(effects
				(font
					(size 1.27 1.27)
					(thickness 0.15)
				)
				(justify left bottom)
				(hide yes)
			)
		)
		(property "Datasheet" ""
			(at 156.21 67.31 0)
			(effects
				(font
					(size 1.27 1.27)
					(thickness 0.15)
				)
				(justify left bottom)
				(hide yes)
			)
		)
		(property "Description" ""
			(at 140.97 57.15 0)
			(effects
				(font
					(size 1.27 1.27)
				)
				(hide yes)
			)
		)
		(property "Author" "Antmicro"
			(at 156.21 64.77 0)
			(effects
				(font
					(size 1.27 1.27)
					(thickness 0.15)
				)
				(justify left bottom)
				(hide yes)
			)
		)
		(property "License" "Apache-2.0"
			(at 156.21 67.31 0)
			(effects
				(font
					(size 1.27 1.27)
					(thickness 0.15)
				)
				(justify left bottom)
				(hide yes)
			)
		)
		(pin "1"
		)
		(instances
			(project "polarfire-som"
				(path ""
					(reference "#PWR0258")
					(unit 1)
				)
			)
		)
	)
	(symbol
		(lib_id "antmicroCapacitors0402:C_100n_0402")
		(at 130.81 212.09 90)
		(unit 1)
		(exclude_from_sim no)
		(in_bom yes)
		(on_board yes)
		(dnp no)
		(property "Reference" "C224"
			(at 133.35 208.2735 90)
			(effects
				(font
					(size 1.27 1.27)
					(thickness 0.15)
				)
				(justify right)
			)
		)
		(property "Value" "C_100n_0402"
			(at 140.97 191.77 0)
			(effects
				(font
					(size 1.27 1.27)
					(thickness 0.15)
				)
				(justify left bottom)
				(hide yes)
			)
		)
		(property "Footprint" "antmicro-footprints:C_0402_1005Metric"
			(at 143.51 191.77 0)
			(effects
				(font
					(size 1.27 1.27)
					(thickness 0.15)
				)
				(justify left bottom)
				(hide yes)
			)
		)
		(property "Datasheet" "https://www.murata.com/products/productdetail?partno=GRM155R61H104KE14%23"
			(at 146.05 191.77 0)
			(effects
				(font
					(size 1.27 1.27)
					(thickness 0.15)
				)
				(justify left bottom)
				(hide yes)
			)
		)
		(property "Description" "SMD Multilayer Ceramic Capacitor, 0.1 µF, 50 V, 0402 [1005 Metric], ± 10%, X5R, GRM Series"
			(at 130.81 212.09 0)
			(effects
				(font
					(size 1.27 1.27)
				)
				(hide yes)
			)
		)
		(property "MPN" "GRM155R61H104KE14D"
			(at 148.59 191.77 0)
			(effects
				(font
					(size 1.27 1.27)
					(thickness 0.15)
				)
				(justify left bottom)
				(hide yes)
			)
		)
		(property "Manufacturer" "Murata"
			(at 151.13 191.77 0)
			(effects
				(font
					(size 1.27 1.27)
					(thickness 0.15)
				)
				(justify left bottom)
				(hide yes)
			)
		)
		(property "License" "Apache-2.0"
			(at 153.67 191.77 0)
			(effects
				(font
					(size 1.27 1.27)
					(thickness 0.15)
				)
				(justify left bottom)
				(hide yes)
			)
		)
		(property "Author" "Antmicro"
			(at 156.21 191.77 0)
			(effects
				(font
					(size 1.27 1.27)
					(thickness 0.15)
				)
				(justify left bottom)
				(hide yes)
			)
		)
		(property "Val" "100n"
			(at 138.43 210.185 90)
			(effects
				(font
					(size 1.27 1.27)
					(thickness 0.15)
				)
				(justify left bottom)
			)
		)
		(property "Voltage" "50V"
			(at 158.75 191.77 0)
			(effects
				(font
					(size 1.27 1.27)
				)
				(justify left bottom)
				(hide yes)
			)
		)
		(property "Dielectric" "X5R"
			(at 161.29 191.77 0)
			(effects
				(font
					(size 1.27 1.27)
				)
				(justify left bottom)
				(hide yes)
			)
		)
		(property "Public" ""
			(at 163.83 191.77 0)
			(effects
				(font
					(size 1.27 1.27)
				)
				(justify left bottom)
				(hide yes)
			)
		)
		(pin "1"
		)
		(pin "2"
		)
		(instances
			(project "polarfire-som"
				(path ""
					(reference "C224")
					(unit 1)
				)
			)
		)
	)
	(symbol
		(lib_id "antmicroCapacitors0402:C_1u_0402")
		(at 66.04 250.19 270)
		(mirror x)
		(unit 1)
		(exclude_from_sim no)
		(in_bom yes)
		(on_board yes)
		(dnp no)
		(fields_autoplaced yes)
		(property "Reference" "C116"
			(at 63.5 246.3735 90)
			(effects
				(font
					(size 1.27 1.27)
					(thickness 0.15)
				)
				(justify right)
			)
		)
		(property "Value" "C_1u_0402"
			(at 55.88 229.87 0)
			(effects
				(font
					(size 1.27 1.27)
					(thickness 0.15)
				)
				(justify left bottom)
				(hide yes)
			)
		)
		(property "Footprint" "antmicro-footprints:C_0402_1005Metric"
			(at 53.34 229.87 0)
			(effects
				(font
					(size 1.27 1.27)
					(thickness 0.15)
				)
				(justify left bottom)
				(hide yes)
			)
		)
		(property "Datasheet" "https://product.tdk.com/en/search/capacitor/ceramic/mlcc/info?part_no=C1005X6S1A105K050BC"
			(at 50.8 229.87 0)
			(effects
				(font
					(size 1.27 1.27)
					(thickness 0.15)
				)
				(justify left bottom)
				(hide yes)
			)
		)
		(property "Description" "SMD Multilayer Ceramic Capacitor, 1 µF, 10 V, 0402 [1005 Metric], ± 10%, X6S, C"
			(at 66.04 250.19 0)
			(effects
				(font
					(size 1.27 1.27)
				)
				(hide yes)
			)
		)
		(property "MPN" "C1005X6S1A105K050BC"
			(at 48.26 229.87 0)
			(effects
				(font
					(size 1.27 1.27)
					(thickness 0.15)
				)
				(justify left bottom)
				(hide yes)
			)
		)
		(property "Manufacturer" "TDK"
			(at 45.72 229.87 0)
			(effects
				(font
					(size 1.27 1.27)
					(thickness 0.15)
				)
				(justify left bottom)
				(hide yes)
			)
		)
		(property "License" "Apache-2.0"
			(at 43.18 229.87 0)
			(effects
				(font
					(size 1.27 1.27)
					(thickness 0.15)
				)
				(justify left bottom)
				(hide yes)
			)
		)
		(property "Author" "Antmicro"
			(at 40.64 229.87 0)
			(effects
				(font
					(size 1.27 1.27)
					(thickness 0.15)
				)
				(justify left bottom)
				(hide yes)
			)
		)
		(property "Val" "1u"
			(at 63.5 248.9135 90)
			(effects
				(font
					(size 1.27 1.27)
					(thickness 0.15)
				)
				(justify right)
			)
		)
		(property "Voltage" ""
			(at 38.1 229.87 0)
			(effects
				(font
					(size 1.27 1.27)
				)
				(justify left bottom)
				(hide yes)
			)
		)
		(property "Dielectric" ""
			(at 35.56 229.87 0)
			(effects
				(font
					(size 1.27 1.27)
				)
				(justify left bottom)
				(hide yes)
			)
		)
		(property "Public" ""
			(at 33.02 229.87 0)
			(effects
				(font
					(size 1.27 1.27)
				)
				(justify left bottom)
				(hide yes)
			)
		)
		(pin "1"
		)
		(pin "2"
		)
		(instances
			(project "polarfire-som"
				(path ""
					(reference "C116")
					(unit 1)
				)
			)
		)
	)
	(symbol
		(lib_id "antmicropower:GND")
		(at 313.69 204.47 0)
		(unit 1)
		(exclude_from_sim no)
		(in_bom yes)
		(on_board yes)
		(dnp no)
		(property "Reference" "#PWR0357"
			(at 322.58 207.01 0)
			(effects
				(font
					(size 1.27 1.27)
					(thickness 0.15)
				)
				(justify left bottom)
				(hide yes)
			)
		)
		(property "Value" "GND"
			(at 313.69 208.28 0)
			(effects
				(font
					(size 1.27 1.27)
					(thickness 0.15)
				)
			)
		)
		(property "Footprint" ""
			(at 322.58 212.09 0)
			(effects
				(font
					(size 1.27 1.27)
					(thickness 0.15)
				)
				(justify left bottom)
				(hide yes)
			)
		)
		(property "Datasheet" ""
			(at 322.58 217.17 0)
			(effects
				(font
					(size 1.27 1.27)
					(thickness 0.15)
				)
				(justify left bottom)
				(hide yes)
			)
		)
		(property "Description" ""
			(at 313.69 204.47 0)
			(effects
				(font
					(size 1.27 1.27)
				)
				(hide yes)
			)
		)
		(property "Author" "Antmicro"
			(at 322.58 212.09 0)
			(effects
				(font
					(size 1.27 1.27)
					(thickness 0.15)
				)
				(justify left bottom)
				(hide yes)
			)
		)
		(property "License" "Apache-2.0"
			(at 322.58 214.63 0)
			(effects
				(font
					(size 1.27 1.27)
					(thickness 0.15)
				)
				(justify left bottom)
				(hide yes)
			)
		)
		(pin "1"
		)
		(instances
			(project "polarfire-som"
				(path ""
					(reference "#PWR0357")
					(unit 1)
				)
			)
		)
	)
	(symbol
		(lib_id "antmicroCapacitors0402:C_100n_0402")
		(at 166.37 104.14 0)
		(mirror y)
		(unit 1)
		(exclude_from_sim no)
		(in_bom yes)
		(on_board yes)
		(dnp no)
		(property "Reference" "C257"
			(at 161.29 102.87 0)
			(effects
				(font
					(size 1.27 1.27)
					(thickness 0.15)
				)
				(justify left)
			)
		)
		(property "Value" "C_100n_0402"
			(at 146.05 114.3 0)
			(effects
				(font
					(size 1.27 1.27)
					(thickness 0.15)
				)
				(justify left bottom)
				(hide yes)
			)
		)
		(property "Footprint" "antmicro-footprints:C_0402_1005Metric"
			(at 146.05 116.84 0)
			(effects
				(font
					(size 1.27 1.27)
					(thickness 0.15)
				)
				(justify left bottom)
				(hide yes)
			)
		)
		(property "Datasheet" "https://www.murata.com/products/productdetail?partno=GRM155R61H104KE14%23"
			(at 146.05 119.38 0)
			(effects
				(font
					(size 1.27 1.27)
					(thickness 0.15)
				)
				(justify left bottom)
				(hide yes)
			)
		)
		(property "Description" "SMD Multilayer Ceramic Capacitor, 0.1 µF, 50 V, 0402 [1005 Metric], ± 10%, X5R, GRM Series"
			(at 166.37 104.14 0)
			(effects
				(font
					(size 1.27 1.27)
				)
				(hide yes)
			)
		)
		(property "MPN" "GRM155R61H104KE14D"
			(at 146.05 121.92 0)
			(effects
				(font
					(size 1.27 1.27)
					(thickness 0.15)
				)
				(justify left bottom)
				(hide yes)
			)
		)
		(property "Manufacturer" "Murata"
			(at 146.05 124.46 0)
			(effects
				(font
					(size 1.27 1.27)
					(thickness 0.15)
				)
				(justify left bottom)
				(hide yes)
			)
		)
		(property "License" "Apache-2.0"
			(at 146.05 127 0)
			(effects
				(font
					(size 1.27 1.27)
					(thickness 0.15)
				)
				(justify left bottom)
				(hide yes)
			)
		)
		(property "Author" "Antmicro"
			(at 146.05 129.54 0)
			(effects
				(font
					(size 1.27 1.27)
					(thickness 0.15)
				)
				(justify left bottom)
				(hide yes)
			)
		)
		(property "Val" "100n"
			(at 173.99 104.14 0)
			(effects
				(font
					(size 1.27 1.27)
					(thickness 0.15)
				)
				(justify left bottom)
			)
		)
		(property "Voltage" "50V"
			(at 146.05 132.08 0)
			(effects
				(font
					(size 1.27 1.27)
				)
				(justify left bottom)
				(hide yes)
			)
		)
		(property "Dielectric" "X5R"
			(at 146.05 134.62 0)
			(effects
				(font
					(size 1.27 1.27)
				)
				(justify left bottom)
				(hide yes)
			)
		)
		(property "Public" ""
			(at 146.05 137.16 0)
			(effects
				(font
					(size 1.27 1.27)
				)
				(justify left bottom)
				(hide yes)
			)
		)
		(pin "1"
		)
		(pin "2"
		)
		(instances
			(project "polarfire-som"
				(path ""
					(reference "C257")
					(unit 1)
				)
			)
		)
	)
	(symbol
		(lib_id "antmicropower:GND")
		(at 330.2 204.47 0)
		(unit 1)
		(exclude_from_sim no)
		(in_bom yes)
		(on_board yes)
		(dnp no)
		(property "Reference" "#PWR0169"
			(at 339.09 207.01 0)
			(effects
				(font
					(size 1.27 1.27)
					(thickness 0.15)
				)
				(justify left bottom)
				(hide yes)
			)
		)
		(property "Value" "GND"
			(at 330.2 208.28 0)
			(effects
				(font
					(size 1.27 1.27)
					(thickness 0.15)
				)
			)
		)
		(property "Footprint" ""
			(at 339.09 212.09 0)
			(effects
				(font
					(size 1.27 1.27)
					(thickness 0.15)
				)
				(justify left bottom)
				(hide yes)
			)
		)
		(property "Datasheet" ""
			(at 339.09 217.17 0)
			(effects
				(font
					(size 1.27 1.27)
					(thickness 0.15)
				)
				(justify left bottom)
				(hide yes)
			)
		)
		(property "Description" ""
			(at 330.2 204.47 0)
			(effects
				(font
					(size 1.27 1.27)
				)
				(hide yes)
			)
		)
		(property "Author" "Antmicro"
			(at 339.09 212.09 0)
			(effects
				(font
					(size 1.27 1.27)
					(thickness 0.15)
				)
				(justify left bottom)
				(hide yes)
			)
		)
		(property "License" "Apache-2.0"
			(at 339.09 214.63 0)
			(effects
				(font
					(size 1.27 1.27)
					(thickness 0.15)
				)
				(justify left bottom)
				(hide yes)
			)
		)
		(pin "1"
		)
		(instances
			(project "polarfire-som"
				(path ""
					(reference "#PWR0169")
					(unit 1)
				)
			)
		)
	)
	(symbol
		(lib_id "antmicroCapacitors0402:C_100n_0402")
		(at 166.37 99.06 0)
		(mirror y)
		(unit 1)
		(exclude_from_sim no)
		(in_bom yes)
		(on_board yes)
		(dnp yes)
		(property "Reference" "C256"
			(at 161.29 97.79 0)
			(effects
				(font
					(size 1.27 1.27)
					(thickness 0.15)
				)
				(justify left)
			)
		)
		(property "Value" "C_100n_0402"
			(at 146.05 109.22 0)
			(effects
				(font
					(size 1.27 1.27)
					(thickness 0.15)
				)
				(justify left bottom)
				(hide yes)
			)
		)
		(property "Footprint" "antmicro-footprints:C_0402_1005Metric"
			(at 146.05 111.76 0)
			(effects
				(font
					(size 1.27 1.27)
					(thickness 0.15)
				)
				(justify left bottom)
				(hide yes)
			)
		)
		(property "Datasheet" "https://www.murata.com/products/productdetail?partno=GRM155R61H104KE14%23"
			(at 146.05 114.3 0)
			(effects
				(font
					(size 1.27 1.27)
					(thickness 0.15)
				)
				(justify left bottom)
				(hide yes)
			)
		)
		(property "Description" "SMD Multilayer Ceramic Capacitor, 0.1 µF, 50 V, 0402 [1005 Metric], ± 10%, X5R, GRM Series"
			(at 166.37 99.06 0)
			(effects
				(font
					(size 1.27 1.27)
				)
				(hide yes)
			)
		)
		(property "MPN" "GRM155R61H104KE14D"
			(at 146.05 116.84 0)
			(effects
				(font
					(size 1.27 1.27)
					(thickness 0.15)
				)
				(justify left bottom)
				(hide yes)
			)
		)
		(property "Manufacturer" "Murata"
			(at 146.05 119.38 0)
			(effects
				(font
					(size 1.27 1.27)
					(thickness 0.15)
				)
				(justify left bottom)
				(hide yes)
			)
		)
		(property "License" "Apache-2.0"
			(at 146.05 121.92 0)
			(effects
				(font
					(size 1.27 1.27)
					(thickness 0.15)
				)
				(justify left bottom)
				(hide yes)
			)
		)
		(property "Author" "Antmicro"
			(at 146.05 124.46 0)
			(effects
				(font
					(size 1.27 1.27)
					(thickness 0.15)
				)
				(justify left bottom)
				(hide yes)
			)
		)
		(property "Val" "100n"
			(at 176.53 99.06 0)
			(effects
				(font
					(size 1.27 1.27)
					(thickness 0.15)
				)
				(justify left bottom)
			)
		)
		(property "Voltage" "50V"
			(at 146.05 127 0)
			(effects
				(font
					(size 1.27 1.27)
				)
				(justify left bottom)
				(hide yes)
			)
		)
		(property "Dielectric" "X5R"
			(at 146.05 129.54 0)
			(effects
				(font
					(size 1.27 1.27)
				)
				(justify left bottom)
				(hide yes)
			)
		)
		(property "DNP" "DNP"
			(at 171.45 99.06 0)
			(effects
				(font
					(size 1.27 1.27)
					(bold yes)
				)
				(justify left bottom)
				(hide yes)
			)
		)
		(property "Public" ""
			(at 146.05 132.08 0)
			(effects
				(font
					(size 1.27 1.27)
				)
				(justify left bottom)
				(hide yes)
			)
		)
		(pin "1"
		)
		(pin "2"
		)
		(instances
			(project "polarfire-som"
				(path ""
					(reference "C256")
					(unit 1)
				)
			)
		)
	)
	(symbol
		(lib_id "antmicropower:GND")
		(at 105.41 213.36 0)
		(unit 1)
		(exclude_from_sim no)
		(in_bom yes)
		(on_board yes)
		(dnp no)
		(property "Reference" "#PWR0230"
			(at 114.3 215.9 0)
			(effects
				(font
					(size 1.27 1.27)
					(thickness 0.15)
				)
				(justify left bottom)
				(hide yes)
			)
		)
		(property "Value" "GND"
			(at 105.41 217.17 0)
			(effects
				(font
					(size 1.27 1.27)
					(thickness 0.15)
				)
			)
		)
		(property "Footprint" ""
			(at 114.3 220.98 0)
			(effects
				(font
					(size 1.27 1.27)
					(thickness 0.15)
				)
				(justify left bottom)
				(hide yes)
			)
		)
		(property "Datasheet" ""
			(at 114.3 226.06 0)
			(effects
				(font
					(size 1.27 1.27)
					(thickness 0.15)
				)
				(justify left bottom)
				(hide yes)
			)
		)
		(property "Description" ""
			(at 105.41 213.36 0)
			(effects
				(font
					(size 1.27 1.27)
				)
				(hide yes)
			)
		)
		(property "Author" "Antmicro"
			(at 114.3 220.98 0)
			(effects
				(font
					(size 1.27 1.27)
					(thickness 0.15)
				)
				(justify left bottom)
				(hide yes)
			)
		)
		(property "License" "Apache-2.0"
			(at 114.3 223.52 0)
			(effects
				(font
					(size 1.27 1.27)
					(thickness 0.15)
				)
				(justify left bottom)
				(hide yes)
			)
		)
		(pin "1"
		)
		(instances
			(project "polarfire-som"
				(path ""
					(reference "#PWR0230")
					(unit 1)
				)
			)
		)
	)
	(symbol
		(lib_id "antmicropower:GND")
		(at 130.81 270.51 0)
		(unit 1)
		(exclude_from_sim no)
		(in_bom yes)
		(on_board yes)
		(dnp no)
		(property "Reference" "#PWR0243"
			(at 139.7 273.05 0)
			(effects
				(font
					(size 1.27 1.27)
					(thickness 0.15)
				)
				(justify left bottom)
				(hide yes)
			)
		)
		(property "Value" "GND"
			(at 130.81 274.32 0)
			(effects
				(font
					(size 1.27 1.27)
					(thickness 0.15)
				)
			)
		)
		(property "Footprint" ""
			(at 139.7 278.13 0)
			(effects
				(font
					(size 1.27 1.27)
					(thickness 0.15)
				)
				(justify left bottom)
				(hide yes)
			)
		)
		(property "Datasheet" ""
			(at 139.7 283.21 0)
			(effects
				(font
					(size 1.27 1.27)
					(thickness 0.15)
				)
				(justify left bottom)
				(hide yes)
			)
		)
		(property "Description" ""
			(at 130.81 270.51 0)
			(effects
				(font
					(size 1.27 1.27)
				)
				(hide yes)
			)
		)
		(property "Author" "Antmicro"
			(at 139.7 278.13 0)
			(effects
				(font
					(size 1.27 1.27)
					(thickness 0.15)
				)
				(justify left bottom)
				(hide yes)
			)
		)
		(property "License" "Apache-2.0"
			(at 139.7 280.67 0)
			(effects
				(font
					(size 1.27 1.27)
					(thickness 0.15)
				)
				(justify left bottom)
				(hide yes)
			)
		)
		(pin "1"
		)
		(instances
			(project "polarfire-som"
				(path ""
					(reference "#PWR0243")
					(unit 1)
				)
			)
		)
	)
	(symbol
		(lib_id "antmicropower:+2V5")
		(at 99.06 205.74 0)
		(unit 1)
		(exclude_from_sim no)
		(in_bom yes)
		(on_board yes)
		(dnp no)
		(property "Reference" "#PWR0226"
			(at 99.06 209.55 0)
			(effects
				(font
					(size 1.27 1.27)
				)
				(hide yes)
			)
		)
		(property "Value" "+2V5"
			(at 99.06 201.93 0)
			(effects
				(font
					(size 1.27 1.27)
				)
			)
		)
		(property "Footprint" ""
			(at 99.06 205.74 0)
			(effects
				(font
					(size 1.27 1.27)
				)
				(hide yes)
			)
		)
		(property "Datasheet" ""
			(at 99.06 205.74 0)
			(effects
				(font
					(size 1.27 1.27)
				)
				(hide yes)
			)
		)
		(property "Description" ""
			(at 99.06 205.74 0)
			(effects
				(font
					(size 1.27 1.27)
				)
				(hide yes)
			)
		)
		(pin "1"
		)
		(instances
			(project "polarfire-som"
				(path ""
					(reference "#PWR0226")
					(unit 1)
				)
			)
		)
	)
	(symbol
		(lib_id "antmicropower:+2V5")
		(at 99.06 186.69 0)
		(unit 1)
		(exclude_from_sim no)
		(in_bom yes)
		(on_board yes)
		(dnp no)
		(property "Reference" "#PWR0225"
			(at 99.06 190.5 0)
			(effects
				(font
					(size 1.27 1.27)
				)
				(hide yes)
			)
		)
		(property "Value" "+2V5"
			(at 99.06 182.88 0)
			(effects
				(font
					(size 1.27 1.27)
				)
			)
		)
		(property "Footprint" ""
			(at 99.06 186.69 0)
			(effects
				(font
					(size 1.27 1.27)
				)
				(hide yes)
			)
		)
		(property "Datasheet" ""
			(at 99.06 186.69 0)
			(effects
				(font
					(size 1.27 1.27)
				)
				(hide yes)
			)
		)
		(property "Description" ""
			(at 99.06 186.69 0)
			(effects
				(font
					(size 1.27 1.27)
				)
				(hide yes)
			)
		)
		(pin "1"
		)
		(instances
			(project "polarfire-som"
				(path ""
					(reference "#PWR0225")
					(unit 1)
				)
			)
		)
	)
	(symbol
		(lib_id "antmicropower:GND")
		(at 72.39 194.31 0)
		(unit 1)
		(exclude_from_sim no)
		(in_bom yes)
		(on_board yes)
		(dnp no)
		(property "Reference" "#PWR0239"
			(at 81.28 196.85 0)
			(effects
				(font
					(size 1.27 1.27)
					(thickness 0.15)
				)
				(justify left bottom)
				(hide yes)
			)
		)
		(property "Value" "GND"
			(at 72.39 198.12 0)
			(effects
				(font
					(size 1.27 1.27)
					(thickness 0.15)
				)
			)
		)
		(property "Footprint" ""
			(at 81.28 201.93 0)
			(effects
				(font
					(size 1.27 1.27)
					(thickness 0.15)
				)
				(justify left bottom)
				(hide yes)
			)
		)
		(property "Datasheet" ""
			(at 81.28 207.01 0)
			(effects
				(font
					(size 1.27 1.27)
					(thickness 0.15)
				)
				(justify left bottom)
				(hide yes)
			)
		)
		(property "Description" ""
			(at 72.39 194.31 0)
			(effects
				(font
					(size 1.27 1.27)
				)
				(hide yes)
			)
		)
		(property "Author" "Antmicro"
			(at 81.28 201.93 0)
			(effects
				(font
					(size 1.27 1.27)
					(thickness 0.15)
				)
				(justify left bottom)
				(hide yes)
			)
		)
		(property "License" "Apache-2.0"
			(at 81.28 204.47 0)
			(effects
				(font
					(size 1.27 1.27)
					(thickness 0.15)
				)
				(justify left bottom)
				(hide yes)
			)
		)
		(pin "1"
		)
		(instances
			(project "polarfire-som"
				(path ""
					(reference "#PWR0239")
					(unit 1)
				)
			)
		)
	)
	(symbol
		(lib_id "antmicropower:GND")
		(at 137.16 194.31 0)
		(unit 1)
		(exclude_from_sim no)
		(in_bom yes)
		(on_board yes)
		(dnp no)
		(property "Reference" "#PWR0245"
			(at 146.05 196.85 0)
			(effects
				(font
					(size 1.27 1.27)
					(thickness 0.15)
				)
				(justify left bottom)
				(hide yes)
			)
		)
		(property "Value" "GND"
			(at 137.16 198.12 0)
			(effects
				(font
					(size 1.27 1.27)
					(thickness 0.15)
				)
			)
		)
		(property "Footprint" ""
			(at 146.05 201.93 0)
			(effects
				(font
					(size 1.27 1.27)
					(thickness 0.15)
				)
				(justify left bottom)
				(hide yes)
			)
		)
		(property "Datasheet" ""
			(at 146.05 207.01 0)
			(effects
				(font
					(size 1.27 1.27)
					(thickness 0.15)
				)
				(justify left bottom)
				(hide yes)
			)
		)
		(property "Description" ""
			(at 137.16 194.31 0)
			(effects
				(font
					(size 1.27 1.27)
				)
				(hide yes)
			)
		)
		(property "Author" "Antmicro"
			(at 146.05 201.93 0)
			(effects
				(font
					(size 1.27 1.27)
					(thickness 0.15)
				)
				(justify left bottom)
				(hide yes)
			)
		)
		(property "License" "Apache-2.0"
			(at 146.05 204.47 0)
			(effects
				(font
					(size 1.27 1.27)
					(thickness 0.15)
				)
				(justify left bottom)
				(hide yes)
			)
		)
		(pin "1"
		)
		(instances
			(project "polarfire-som"
				(path ""
					(reference "#PWR0245")
					(unit 1)
				)
			)
		)
	)
	(symbol
		(lib_id "antmicropower:+3V3")
		(at 66.04 224.79 0)
		(unit 1)
		(exclude_from_sim no)
		(in_bom yes)
		(on_board yes)
		(dnp no)
		(fields_autoplaced yes)
		(property "Reference" "#PWR0298"
			(at 81.28 227.33 0)
			(effects
				(font
					(size 1.27 1.27)
					(thickness 0.15)
				)
				(justify left bottom)
				(hide yes)
			)
		)
		(property "Value" "+3V3"
			(at 66.04 219.71 0)
			(effects
				(font
					(size 1.27 1.27)
					(thickness 0.15)
				)
			)
		)
		(property "Footprint" ""
			(at 81.28 232.41 0)
			(effects
				(font
					(size 1.27 1.27)
					(thickness 0.15)
				)
				(justify left bottom)
				(hide yes)
			)
		)
		(property "Datasheet" ""
			(at 81.28 234.95 0)
			(effects
				(font
					(size 1.27 1.27)
					(thickness 0.15)
				)
				(justify left bottom)
				(hide yes)
			)
		)
		(property "Description" ""
			(at 66.04 224.79 0)
			(effects
				(font
					(size 1.27 1.27)
				)
				(hide yes)
			)
		)
		(property "Author" "Antmicro"
			(at 81.28 232.41 0)
			(effects
				(font
					(size 1.27 1.27)
					(thickness 0.15)
				)
				(justify left bottom)
				(hide yes)
			)
		)
		(property "License" "Apache-2.0"
			(at 81.28 234.95 0)
			(effects
				(font
					(size 1.27 1.27)
					(thickness 0.15)
				)
				(justify left bottom)
				(hide yes)
			)
		)
		(pin "1"
		)
		(instances
			(project "polarfire-som"
				(path ""
					(reference "#PWR0298")
					(unit 1)
				)
			)
		)
	)
	(symbol
		(lib_id "antmicropower:+1V05")
		(at 130.81 243.84 0)
		(unit 1)
		(exclude_from_sim no)
		(in_bom yes)
		(on_board yes)
		(dnp no)
		(property "Reference" "#PWR0240"
			(at 130.81 247.65 0)
			(effects
				(font
					(size 1.27 1.27)
				)
				(hide yes)
			)
		)
		(property "Value" "+1V05"
			(at 130.81 240.03 0)
			(effects
				(font
					(size 1.27 1.27)
				)
			)
		)
		(property "Footprint" ""
			(at 130.81 243.84 0)
			(effects
				(font
					(size 1.27 1.27)
				)
				(hide yes)
			)
		)
		(property "Datasheet" ""
			(at 130.81 243.84 0)
			(effects
				(font
					(size 1.27 1.27)
				)
				(hide yes)
			)
		)
		(property "Description" ""
			(at 130.81 243.84 0)
			(effects
				(font
					(size 1.27 1.27)
				)
				(hide yes)
			)
		)
		(pin "1"
		)
		(instances
			(project "polarfire-som"
				(path ""
					(reference "#PWR0240")
					(unit 1)
				)
			)
		)
	)
	(symbol
		(lib_id "antmicroCapacitors0402:C_1u_0402")
		(at 130.81 231.14 270)
		(mirror x)
		(unit 1)
		(exclude_from_sim no)
		(in_bom yes)
		(on_board yes)
		(dnp no)
		(property "Reference" "C251"
			(at 133.35 227.3235 90)
			(effects
				(font
					(size 1.27 1.27)
					(thickness 0.15)
				)
				(justify left)
			)
		)
		(property "Value" "C_1u_0402"
			(at 120.65 210.82 0)
			(effects
				(font
					(size 1.27 1.27)
					(thickness 0.15)
				)
				(justify left bottom)
				(hide yes)
			)
		)
		(property "Footprint" "antmicro-footprints:C_0402_1005Metric"
			(at 118.11 210.82 0)
			(effects
				(font
					(size 1.27 1.27)
					(thickness 0.15)
				)
				(justify left bottom)
				(hide yes)
			)
		)
		(property "Datasheet" "https://product.tdk.com/en/search/capacitor/ceramic/mlcc/info?part_no=C1005X6S1A105K050BC"
			(at 115.57 210.82 0)
			(effects
				(font
					(size 1.27 1.27)
					(thickness 0.15)
				)
				(justify left bottom)
				(hide yes)
			)
		)
		(property "Description" "SMD Multilayer Ceramic Capacitor, 1 µF, 10 V, 0402 [1005 Metric], ± 10%, X6S, C"
			(at 130.81 231.14 0)
			(effects
				(font
					(size 1.27 1.27)
				)
				(hide yes)
			)
		)
		(property "MPN" "C1005X6S1A105K050BC"
			(at 113.03 210.82 0)
			(effects
				(font
					(size 1.27 1.27)
					(thickness 0.15)
				)
				(justify left bottom)
				(hide yes)
			)
		)
		(property "Manufacturer" "TDK"
			(at 110.49 210.82 0)
			(effects
				(font
					(size 1.27 1.27)
					(thickness 0.15)
				)
				(justify left bottom)
				(hide yes)
			)
		)
		(property "License" "Apache-2.0"
			(at 107.95 210.82 0)
			(effects
				(font
					(size 1.27 1.27)
					(thickness 0.15)
				)
				(justify left bottom)
				(hide yes)
			)
		)
		(property "Author" "Antmicro"
			(at 105.41 210.82 0)
			(effects
				(font
					(size 1.27 1.27)
					(thickness 0.15)
				)
				(justify left bottom)
				(hide yes)
			)
		)
		(property "Val" "1u"
			(at 133.35 229.8635 90)
			(effects
				(font
					(size 1.27 1.27)
					(thickness 0.15)
				)
				(justify left)
			)
		)
		(property "Voltage" ""
			(at 102.87 210.82 0)
			(effects
				(font
					(size 1.27 1.27)
				)
				(justify left bottom)
				(hide yes)
			)
		)
		(property "Dielectric" ""
			(at 100.33 210.82 0)
			(effects
				(font
					(size 1.27 1.27)
				)
				(justify left bottom)
				(hide yes)
			)
		)
		(property "Public" ""
			(at 97.79 210.82 0)
			(effects
				(font
					(size 1.27 1.27)
				)
				(justify left bottom)
				(hide yes)
			)
		)
		(pin "1"
		)
		(pin "2"
		)
		(instances
			(project "polarfire-som"
				(path ""
					(reference "C251")
					(unit 1)
				)
			)
		)
	)
	(symbol
		(lib_id "antmicroCapacitors0402:C_100n_0402")
		(at 168.91 78.74 180)
		(unit 1)
		(exclude_from_sim no)
		(in_bom yes)
		(on_board yes)
		(dnp no)
		(property "Reference" "C261"
			(at 162.56 77.47 0)
			(effects
				(font
					(size 1.27 1.27)
					(thickness 0.15)
				)
				(justify left)
			)
		)
		(property "Value" "C_100n_0402"
			(at 148.59 68.58 0)
			(effects
				(font
					(size 1.27 1.27)
					(thickness 0.15)
				)
				(justify left bottom)
				(hide yes)
			)
		)
		(property "Footprint" "antmicro-footprints:C_0402_1005Metric"
			(at 148.59 66.04 0)
			(effects
				(font
					(size 1.27 1.27)
					(thickness 0.15)
				)
				(justify left bottom)
				(hide yes)
			)
		)
		(property "Datasheet" "https://www.murata.com/products/productdetail?partno=GRM155R61H104KE14%23"
			(at 148.59 63.5 0)
			(effects
				(font
					(size 1.27 1.27)
					(thickness 0.15)
				)
				(justify left bottom)
				(hide yes)
			)
		)
		(property "Description" "SMD Multilayer Ceramic Capacitor, 0.1 µF, 50 V, 0402 [1005 Metric], ± 10%, X5R, GRM Series"
			(at 168.91 78.74 0)
			(effects
				(font
					(size 1.27 1.27)
				)
				(hide yes)
			)
		)
		(property "MPN" "GRM155R61H104KE14D"
			(at 148.59 60.96 0)
			(effects
				(font
					(size 1.27 1.27)
					(thickness 0.15)
				)
				(justify left bottom)
				(hide yes)
			)
		)
		(property "Manufacturer" "Murata"
			(at 148.59 58.42 0)
			(effects
				(font
					(size 1.27 1.27)
					(thickness 0.15)
				)
				(justify left bottom)
				(hide yes)
			)
		)
		(property "License" "Apache-2.0"
			(at 148.59 55.88 0)
			(effects
				(font
					(size 1.27 1.27)
					(thickness 0.15)
				)
				(justify left bottom)
				(hide yes)
			)
		)
		(property "Author" "Antmicro"
			(at 148.59 53.34 0)
			(effects
				(font
					(size 1.27 1.27)
					(thickness 0.15)
				)
				(justify left bottom)
				(hide yes)
			)
		)
		(property "Val" "100n"
			(at 172.72 76.835 0)
			(effects
				(font
					(size 1.27 1.27)
					(thickness 0.15)
				)
				(justify left bottom)
			)
		)
		(property "Voltage" "50V"
			(at 148.59 50.8 0)
			(effects
				(font
					(size 1.27 1.27)
				)
				(justify left bottom)
				(hide yes)
			)
		)
		(property "Dielectric" "X5R"
			(at 148.59 48.26 0)
			(effects
				(font
					(size 1.27 1.27)
				)
				(justify left bottom)
				(hide yes)
			)
		)
		(property "Public" ""
			(at 148.59 45.72 0)
			(effects
				(font
					(size 1.27 1.27)
				)
				(justify left bottom)
				(hide yes)
			)
		)
		(pin "1"
		)
		(pin "2"
		)
		(instances
			(project "polarfire-som"
				(path ""
					(reference "C261")
					(unit 1)
				)
			)
		)
	)
	(symbol
		(lib_id "antmicroCapacitors0402:C_100n_0402")
		(at 105.41 231.14 90)
		(unit 1)
		(exclude_from_sim no)
		(in_bom yes)
		(on_board yes)
		(dnp no)
		(property "Reference" "C214"
			(at 107.95 227.3235 90)
			(effects
				(font
					(size 1.27 1.27)
					(thickness 0.15)
				)
				(justify right)
			)
		)
		(property "Value" "C_100n_0402"
			(at 115.57 210.82 0)
			(effects
				(font
					(size 1.27 1.27)
					(thickness 0.15)
				)
				(justify left bottom)
				(hide yes)
			)
		)
		(property "Footprint" "antmicro-footprints:C_0402_1005Metric"
			(at 118.11 210.82 0)
			(effects
				(font
					(size 1.27 1.27)
					(thickness 0.15)
				)
				(justify left bottom)
				(hide yes)
			)
		)
		(property "Datasheet" "https://www.murata.com/products/productdetail?partno=GRM155R61H104KE14%23"
			(at 120.65 210.82 0)
			(effects
				(font
					(size 1.27 1.27)
					(thickness 0.15)
				)
				(justify left bottom)
				(hide yes)
			)
		)
		(property "Description" "SMD Multilayer Ceramic Capacitor, 0.1 µF, 50 V, 0402 [1005 Metric], ± 10%, X5R, GRM Series"
			(at 105.41 231.14 0)
			(effects
				(font
					(size 1.27 1.27)
				)
				(hide yes)
			)
		)
		(property "MPN" "GRM155R61H104KE14D"
			(at 123.19 210.82 0)
			(effects
				(font
					(size 1.27 1.27)
					(thickness 0.15)
				)
				(justify left bottom)
				(hide yes)
			)
		)
		(property "Manufacturer" "Murata"
			(at 125.73 210.82 0)
			(effects
				(font
					(size 1.27 1.27)
					(thickness 0.15)
				)
				(justify left bottom)
				(hide yes)
			)
		)
		(property "License" "Apache-2.0"
			(at 128.27 210.82 0)
			(effects
				(font
					(size 1.27 1.27)
					(thickness 0.15)
				)
				(justify left bottom)
				(hide yes)
			)
		)
		(property "Author" "Antmicro"
			(at 130.81 210.82 0)
			(effects
				(font
					(size 1.27 1.27)
					(thickness 0.15)
				)
				(justify left bottom)
				(hide yes)
			)
		)
		(property "Val" "100n"
			(at 113.03 229.235 90)
			(effects
				(font
					(size 1.27 1.27)
					(thickness 0.15)
				)
				(justify left bottom)
			)
		)
		(property "Voltage" "50V"
			(at 133.35 210.82 0)
			(effects
				(font
					(size 1.27 1.27)
				)
				(justify left bottom)
				(hide yes)
			)
		)
		(property "Dielectric" "X5R"
			(at 135.89 210.82 0)
			(effects
				(font
					(size 1.27 1.27)
				)
				(justify left bottom)
				(hide yes)
			)
		)
		(property "Public" ""
			(at 138.43 210.82 0)
			(effects
				(font
					(size 1.27 1.27)
				)
				(justify left bottom)
				(hide yes)
			)
		)
		(pin "1"
		)
		(pin "2"
		)
		(instances
			(project "polarfire-som"
				(path ""
					(reference "C214")
					(unit 1)
				)
			)
		)
	)
	(symbol
		(lib_id "antmicropower:GND")
		(at 105.41 232.41 0)
		(unit 1)
		(exclude_from_sim no)
		(in_bom yes)
		(on_board yes)
		(dnp no)
		(property "Reference" "#PWR0231"
			(at 114.3 234.95 0)
			(effects
				(font
					(size 1.27 1.27)
					(thickness 0.15)
				)
				(justify left bottom)
				(hide yes)
			)
		)
		(property "Value" "GND"
			(at 105.41 236.22 0)
			(effects
				(font
					(size 1.27 1.27)
					(thickness 0.15)
				)
			)
		)
		(property "Footprint" ""
			(at 114.3 240.03 0)
			(effects
				(font
					(size 1.27 1.27)
					(thickness 0.15)
				)
				(justify left bottom)
				(hide yes)
			)
		)
		(property "Datasheet" ""
			(at 114.3 245.11 0)
			(effects
				(font
					(size 1.27 1.27)
					(thickness 0.15)
				)
				(justify left bottom)
				(hide yes)
			)
		)
		(property "Description" ""
			(at 105.41 232.41 0)
			(effects
				(font
					(size 1.27 1.27)
				)
				(hide yes)
			)
		)
		(property "Author" "Antmicro"
			(at 114.3 240.03 0)
			(effects
				(font
					(size 1.27 1.27)
					(thickness 0.15)
				)
				(justify left bottom)
				(hide yes)
			)
		)
		(property "License" "Apache-2.0"
			(at 114.3 242.57 0)
			(effects
				(font
					(size 1.27 1.27)
					(thickness 0.15)
				)
				(justify left bottom)
				(hide yes)
			)
		)
		(pin "1"
		)
		(instances
			(project "polarfire-som"
				(path ""
					(reference "#PWR0231")
					(unit 1)
				)
			)
		)
	)
	(symbol
		(lib_id "antmicroCapacitors0402:C_1u_0402")
		(at 130.81 269.24 90)
		(unit 1)
		(exclude_from_sim no)
		(in_bom yes)
		(on_board yes)
		(dnp no)
		(property "Reference" "C253"
			(at 133.985 265.4235 90)
			(effects
				(font
					(size 1.27 1.27)
					(thickness 0.15)
				)
				(justify right)
			)
		)
		(property "Value" "C_1u_0402"
			(at 140.97 248.92 0)
			(effects
				(font
					(size 1.27 1.27)
					(thickness 0.15)
				)
				(justify left bottom)
				(hide yes)
			)
		)
		(property "Footprint" "antmicro-footprints:C_0402_1005Metric"
			(at 143.51 248.92 0)
			(effects
				(font
					(size 1.27 1.27)
					(thickness 0.15)
				)
				(justify left bottom)
				(hide yes)
			)
		)
		(property "Datasheet" "https://product.tdk.com/en/search/capacitor/ceramic/mlcc/info?part_no=C1005X6S1A105K050BC"
			(at 146.05 248.92 0)
			(effects
				(font
					(size 1.27 1.27)
					(thickness 0.15)
				)
				(justify left bottom)
				(hide yes)
			)
		)
		(property "Description" "SMD Multilayer Ceramic Capacitor, 1 µF, 10 V, 0402 [1005 Metric], ± 10%, X6S, C"
			(at 130.81 269.24 0)
			(effects
				(font
					(size 1.27 1.27)
				)
				(hide yes)
			)
		)
		(property "MPN" "C1005X6S1A105K050BC"
			(at 148.59 248.92 0)
			(effects
				(font
					(size 1.27 1.27)
					(thickness 0.15)
				)
				(justify left bottom)
				(hide yes)
			)
		)
		(property "Manufacturer" "TDK"
			(at 151.13 248.92 0)
			(effects
				(font
					(size 1.27 1.27)
					(thickness 0.15)
				)
				(justify left bottom)
				(hide yes)
			)
		)
		(property "License" "Apache-2.0"
			(at 153.67 248.92 0)
			(effects
				(font
					(size 1.27 1.27)
					(thickness 0.15)
				)
				(justify left bottom)
				(hide yes)
			)
		)
		(property "Author" "Antmicro"
			(at 156.21 248.92 0)
			(effects
				(font
					(size 1.27 1.27)
					(thickness 0.15)
				)
				(justify left bottom)
				(hide yes)
			)
		)
		(property "Val" "1u"
			(at 133.985 267.9635 90)
			(effects
				(font
					(size 1.27 1.27)
					(thickness 0.15)
				)
				(justify right)
			)
		)
		(property "Voltage" ""
			(at 158.75 248.92 0)
			(effects
				(font
					(size 1.27 1.27)
				)
				(justify left bottom)
				(hide yes)
			)
		)
		(property "Dielectric" ""
			(at 161.29 248.92 0)
			(effects
				(font
					(size 1.27 1.27)
				)
				(justify left bottom)
				(hide yes)
			)
		)
		(property "Public" ""
			(at 163.83 248.92 0)
			(effects
				(font
					(size 1.27 1.27)
				)
				(justify left bottom)
				(hide yes)
			)
		)
		(pin "1"
		)
		(pin "2"
		)
		(instances
			(project "polarfire-som"
				(path ""
					(reference "C253")
					(unit 1)
				)
			)
		)
	)
	(symbol
		(lib_id "antmicropower:+3V3")
		(at 313.69 189.23 0)
		(unit 1)
		(exclude_from_sim no)
		(in_bom yes)
		(on_board yes)
		(dnp no)
		(property "Reference" "#PWR0356"
			(at 328.93 191.77 0)
			(effects
				(font
					(size 1.27 1.27)
					(thickness 0.15)
				)
				(justify left bottom)
				(hide yes)
			)
		)
		(property "Value" "+3V3"
			(at 313.69 185.42 0)
			(effects
				(font
					(size 1.27 1.27)
					(thickness 0.15)
				)
			)
		)
		(property "Footprint" ""
			(at 328.93 196.85 0)
			(effects
				(font
					(size 1.27 1.27)
					(thickness 0.15)
				)
				(justify left bottom)
				(hide yes)
			)
		)
		(property "Datasheet" ""
			(at 328.93 199.39 0)
			(effects
				(font
					(size 1.27 1.27)
					(thickness 0.15)
				)
				(justify left bottom)
				(hide yes)
			)
		)
		(property "Description" ""
			(at 313.69 189.23 0)
			(effects
				(font
					(size 1.27 1.27)
				)
				(hide yes)
			)
		)
		(property "Author" "Antmicro"
			(at 328.93 196.85 0)
			(effects
				(font
					(size 1.27 1.27)
					(thickness 0.15)
				)
				(justify left bottom)
				(hide yes)
			)
		)
		(property "License" "Apache-2.0"
			(at 328.93 199.39 0)
			(effects
				(font
					(size 1.27 1.27)
					(thickness 0.15)
				)
				(justify left bottom)
				(hide yes)
			)
		)
		(pin "1"
		)
		(instances
			(project "polarfire-som"
				(path ""
					(reference "#PWR0356")
					(unit 1)
				)
			)
		)
	)
	(symbol
		(lib_id "antmicroResistors0402:R_0R_0402")
		(at 63.5 93.98 0)
		(mirror x)
		(unit 1)
		(exclude_from_sim no)
		(in_bom yes)
		(on_board yes)
		(dnp yes)
		(property "Reference" "R12"
			(at 60.96 92.71 0)
			(effects
				(font
					(size 1.27 1.27)
					(thickness 0.15)
				)
			)
		)
		(property "Value" "R_0R_0402"
			(at 83.82 81.28 0)
			(effects
				(font
					(size 1.27 1.27)
					(thickness 0.15)
				)
				(justify left bottom)
				(hide yes)
			)
		)
		(property "Footprint" "antmicro-footprints:R_0402_1005Metric"
			(at 83.82 78.74 0)
			(effects
				(font
					(size 1.27 1.27)
					(thickness 0.15)
				)
				(justify left bottom)
				(hide yes)
			)
		)
		(property "Datasheet" "https://industrial.panasonic.com/cdbs/www-data/pdf/RDA0000/AOA0000C301.pdf"
			(at 83.82 76.2 0)
			(effects
				(font
					(size 1.27 1.27)
					(thickness 0.15)
				)
				(justify left bottom)
				(hide yes)
			)
		)
		(property "Description" "SMD Chip Resistor, Jumper, 0 ohm, 100 mW, 0402 [1005 Metric], Thick Film, General Purpose"
			(at 63.5 93.98 0)
			(effects
				(font
					(size 1.27 1.27)
				)
				(hide yes)
			)
		)
		(property "MPN" "ERJ2GE0R00X"
			(at 83.82 73.66 0)
			(effects
				(font
					(size 1.27 1.27)
					(thickness 0.15)
				)
				(justify left bottom)
				(hide yes)
			)
		)
		(property "Manufacturer" "Panasonic"
			(at 83.82 71.12 0)
			(effects
				(font
					(size 1.27 1.27)
					(thickness 0.15)
				)
				(justify left bottom)
				(hide yes)
			)
		)
		(property "License" "Apache-2.0"
			(at 83.82 68.58 0)
			(effects
				(font
					(size 1.27 1.27)
					(thickness 0.15)
				)
				(justify left bottom)
				(hide yes)
			)
		)
		(property "Author" "Antmicro"
			(at 83.82 66.04 0)
			(effects
				(font
					(size 1.27 1.27)
					(thickness 0.15)
				)
				(justify left bottom)
				(hide yes)
			)
		)
		(property "Val" "0R"
			(at 69.85 92.71 0)
			(effects
				(font
					(size 1.27 1.27)
					(thickness 0.15)
				)
			)
		)
		(property "Tolerance" "~"
			(at 83.82 83.82 0)
			(effects
				(font
					(size 1.27 1.27)
				)
				(justify left bottom)
				(hide yes)
			)
		)
		(property "Current" "1A"
			(at 83.82 63.5 0)
			(effects
				(font
					(size 1.27 1.27)
					(thickness 0.15)
				)
				(justify left bottom)
				(hide yes)
			)
		)
		(property "Public" ""
			(at 83.82 63.5 0)
			(effects
				(font
					(size 1.27 1.27)
				)
				(justify left bottom)
				(hide yes)
			)
		)
		(pin "1"
		)
		(pin "2"
		)
		(instances
			(project "polarfire-som"
				(path ""
					(reference "R12")
					(unit 1)
				)
			)
		)
	)
	(symbol
		(lib_id "antmicropower:GND")
		(at 74.93 87.63 0)
		(unit 1)
		(exclude_from_sim no)
		(in_bom yes)
		(on_board yes)
		(dnp no)
		(property "Reference" "#PWR0220"
			(at 83.82 90.17 0)
			(effects
				(font
					(size 1.27 1.27)
					(thickness 0.15)
				)
				(justify left bottom)
				(hide yes)
			)
		)
		(property "Value" "GND"
			(at 74.93 91.44 0)
			(effects
				(font
					(size 1.27 1.27)
					(thickness 0.15)
				)
			)
		)
		(property "Footprint" ""
			(at 83.82 95.25 0)
			(effects
				(font
					(size 1.27 1.27)
					(thickness 0.15)
				)
				(justify left bottom)
				(hide yes)
			)
		)
		(property "Datasheet" ""
			(at 83.82 100.33 0)
			(effects
				(font
					(size 1.27 1.27)
					(thickness 0.15)
				)
				(justify left bottom)
				(hide yes)
			)
		)
		(property "Description" ""
			(at 74.93 87.63 0)
			(effects
				(font
					(size 1.27 1.27)
				)
				(hide yes)
			)
		)
		(property "Author" "Antmicro"
			(at 83.82 95.25 0)
			(effects
				(font
					(size 1.27 1.27)
					(thickness 0.15)
				)
				(justify left bottom)
				(hide yes)
			)
		)
		(property "License" "Apache-2.0"
			(at 83.82 97.79 0)
			(effects
				(font
					(size 1.27 1.27)
					(thickness 0.15)
				)
				(justify left bottom)
				(hide yes)
			)
		)
		(pin "1"
		)
		(instances
			(project "polarfire-som"
				(path ""
					(reference "#PWR0220")
					(unit 1)
				)
			)
		)
	)
	(symbol
		(lib_id "antmicroCapacitors0402:C_100n_0402")
		(at 105.41 212.09 90)
		(unit 1)
		(exclude_from_sim no)
		(in_bom yes)
		(on_board yes)
		(dnp no)
		(property "Reference" "C213"
			(at 107.95 208.2735 90)
			(effects
				(font
					(size 1.27 1.27)
					(thickness 0.15)
				)
				(justify right)
			)
		)
		(property "Value" "C_100n_0402"
			(at 115.57 191.77 0)
			(effects
				(font
					(size 1.27 1.27)
					(thickness 0.15)
				)
				(justify left bottom)
				(hide yes)
			)
		)
		(property "Footprint" "antmicro-footprints:C_0402_1005Metric"
			(at 118.11 191.77 0)
			(effects
				(font
					(size 1.27 1.27)
					(thickness 0.15)
				)
				(justify left bottom)
				(hide yes)
			)
		)
		(property "Datasheet" "https://www.murata.com/products/productdetail?partno=GRM155R61H104KE14%23"
			(at 120.65 191.77 0)
			(effects
				(font
					(size 1.27 1.27)
					(thickness 0.15)
				)
				(justify left bottom)
				(hide yes)
			)
		)
		(property "Description" "SMD Multilayer Ceramic Capacitor, 0.1 µF, 50 V, 0402 [1005 Metric], ± 10%, X5R, GRM Series"
			(at 105.41 212.09 0)
			(effects
				(font
					(size 1.27 1.27)
				)
				(hide yes)
			)
		)
		(property "MPN" "GRM155R61H104KE14D"
			(at 123.19 191.77 0)
			(effects
				(font
					(size 1.27 1.27)
					(thickness 0.15)
				)
				(justify left bottom)
				(hide yes)
			)
		)
		(property "Manufacturer" "Murata"
			(at 125.73 191.77 0)
			(effects
				(font
					(size 1.27 1.27)
					(thickness 0.15)
				)
				(justify left bottom)
				(hide yes)
			)
		)
		(property "License" "Apache-2.0"
			(at 128.27 191.77 0)
			(effects
				(font
					(size 1.27 1.27)
					(thickness 0.15)
				)
				(justify left bottom)
				(hide yes)
			)
		)
		(property "Author" "Antmicro"
			(at 130.81 191.77 0)
			(effects
				(font
					(size 1.27 1.27)
					(thickness 0.15)
				)
				(justify left bottom)
				(hide yes)
			)
		)
		(property "Val" "100n"
			(at 113.03 210.185 90)
			(effects
				(font
					(size 1.27 1.27)
					(thickness 0.15)
				)
				(justify left bottom)
			)
		)
		(property "Voltage" "50V"
			(at 133.35 191.77 0)
			(effects
				(font
					(size 1.27 1.27)
				)
				(justify left bottom)
				(hide yes)
			)
		)
		(property "Dielectric" "X5R"
			(at 135.89 191.77 0)
			(effects
				(font
					(size 1.27 1.27)
				)
				(justify left bottom)
				(hide yes)
			)
		)
		(property "Public" ""
			(at 138.43 191.77 0)
			(effects
				(font
					(size 1.27 1.27)
				)
				(justify left bottom)
				(hide yes)
			)
		)
		(pin "1"
		)
		(pin "2"
		)
		(instances
			(project "polarfire-som"
				(path ""
					(reference "C213")
					(unit 1)
				)
			)
		)
	)
	(symbol
		(lib_id "antmicropower:GND")
		(at 72.39 232.41 0)
		(unit 1)
		(exclude_from_sim no)
		(in_bom yes)
		(on_board yes)
		(dnp no)
		(property "Reference" "#PWR0223"
			(at 81.28 234.95 0)
			(effects
				(font
					(size 1.27 1.27)
					(thickness 0.15)
				)
				(justify left bottom)
				(hide yes)
			)
		)
		(property "Value" "GND"
			(at 72.39 236.22 0)
			(effects
				(font
					(size 1.27 1.27)
					(thickness 0.15)
				)
			)
		)
		(property "Footprint" ""
			(at 81.28 240.03 0)
			(effects
				(font
					(size 1.27 1.27)
					(thickness 0.15)
				)
				(justify left bottom)
				(hide yes)
			)
		)
		(property "Datasheet" ""
			(at 81.28 245.11 0)
			(effects
				(font
					(size 1.27 1.27)
					(thickness 0.15)
				)
				(justify left bottom)
				(hide yes)
			)
		)
		(property "Description" ""
			(at 72.39 232.41 0)
			(effects
				(font
					(size 1.27 1.27)
				)
				(hide yes)
			)
		)
		(property "Author" "Antmicro"
			(at 81.28 240.03 0)
			(effects
				(font
					(size 1.27 1.27)
					(thickness 0.15)
				)
				(justify left bottom)
				(hide yes)
			)
		)
		(property "License" "Apache-2.0"
			(at 81.28 242.57 0)
			(effects
				(font
					(size 1.27 1.27)
					(thickness 0.15)
				)
				(justify left bottom)
				(hide yes)
			)
		)
		(pin "1"
		)
		(instances
			(project "polarfire-som"
				(path ""
					(reference "#PWR0223")
					(unit 1)
				)
			)
		)
	)
	(symbol
		(lib_id "antmicropower:+2V5")
		(at 147.32 60.96 0)
		(unit 1)
		(exclude_from_sim no)
		(in_bom yes)
		(on_board yes)
		(dnp no)
		(property "Reference" "#PWR0261"
			(at 147.32 64.77 0)
			(effects
				(font
					(size 1.27 1.27)
				)
				(hide yes)
			)
		)
		(property "Value" "+2V5"
			(at 147.32 57.15 0)
			(effects
				(font
					(size 1.27 1.27)
				)
			)
		)
		(property "Footprint" ""
			(at 147.32 60.96 0)
			(effects
				(font
					(size 1.27 1.27)
				)
				(hide yes)
			)
		)
		(property "Datasheet" ""
			(at 147.32 60.96 0)
			(effects
				(font
					(size 1.27 1.27)
				)
				(hide yes)
			)
		)
		(property "Description" ""
			(at 147.32 60.96 0)
			(effects
				(font
					(size 1.27 1.27)
				)
				(hide yes)
			)
		)
		(pin "1"
		)
		(instances
			(project "polarfire-som"
				(path ""
					(reference "#PWR0261")
					(unit 1)
				)
			)
		)
	)
	(symbol
		(lib_id "antmicroResistors0402:R_2k2_0402")
		(at 182.88 113.03 0)
		(unit 1)
		(exclude_from_sim no)
		(in_bom yes)
		(on_board yes)
		(dnp no)
		(property "Reference" "R141"
			(at 180.34 111.76 0)
			(effects
				(font
					(size 1.27 1.27)
					(thickness 0.15)
				)
			)
		)
		(property "Value" "R_2k2_0402"
			(at 203.2 125.73 0)
			(effects
				(font
					(size 1.27 1.27)
					(thickness 0.15)
				)
				(justify left bottom)
				(hide yes)
			)
		)
		(property "Footprint" "antmicro-footprints:R_0402_1005Metric"
			(at 203.2 128.27 0)
			(effects
				(font
					(size 1.27 1.27)
					(thickness 0.15)
				)
				(justify left bottom)
				(hide yes)
			)
		)
		(property "Datasheet" "https://www.bourns.com/docs/product-datasheets/cr.pdf"
			(at 203.2 130.81 0)
			(effects
				(font
					(size 1.27 1.27)
					(thickness 0.15)
				)
				(justify left bottom)
				(hide yes)
			)
		)
		(property "Description" "SMD Chip Resistor, 2.2 kohm, ± 1%, 62.5 mW, 0402 [1005 Metric], Thick Film, General Purpose"
			(at 182.88 113.03 0)
			(effects
				(font
					(size 1.27 1.27)
				)
				(hide yes)
			)
		)
		(property "MPN" "CR0402-FX-2201GLF"
			(at 203.2 133.35 0)
			(effects
				(font
					(size 1.27 1.27)
					(thickness 0.15)
				)
				(justify left bottom)
				(hide yes)
			)
		)
		(property "Manufacturer" "Bourns"
			(at 203.2 135.89 0)
			(effects
				(font
					(size 1.27 1.27)
					(thickness 0.15)
				)
				(justify left bottom)
				(hide yes)
			)
		)
		(property "License" "Apache-2.0"
			(at 203.2 138.43 0)
			(effects
				(font
					(size 1.27 1.27)
					(thickness 0.15)
				)
				(justify left bottom)
				(hide yes)
			)
		)
		(property "Author" "Antmicro"
			(at 203.2 140.97 0)
			(effects
				(font
					(size 1.27 1.27)
					(thickness 0.15)
				)
				(justify left bottom)
				(hide yes)
			)
		)
		(property "Val" "2k2"
			(at 189.23 111.76 0)
			(effects
				(font
					(size 1.27 1.27)
					(thickness 0.15)
				)
			)
		)
		(property "Tolerance" "1%"
			(at 203.2 123.19 0)
			(effects
				(font
					(size 1.27 1.27)
				)
				(justify left bottom)
				(hide yes)
			)
		)
		(property "Public" ""
			(at 203.2 143.51 0)
			(effects
				(font
					(size 1.27 1.27)
				)
				(justify left bottom)
				(hide yes)
			)
		)
		(pin "1"
		)
		(pin "2"
		)
		(instances
			(project "polarfire-som"
				(path ""
					(reference "R141")
					(unit 1)
				)
			)
		)
	)
	(symbol
		(lib_id "antmicropower:GND")
		(at 130.81 213.36 0)
		(unit 1)
		(exclude_from_sim no)
		(in_bom yes)
		(on_board yes)
		(dnp no)
		(property "Reference" "#PWR0236"
			(at 139.7 215.9 0)
			(effects
				(font
					(size 1.27 1.27)
					(thickness 0.15)
				)
				(justify left bottom)
				(hide yes)
			)
		)
		(property "Value" "GND"
			(at 130.81 217.17 0)
			(effects
				(font
					(size 1.27 1.27)
					(thickness 0.15)
				)
			)
		)
		(property "Footprint" ""
			(at 139.7 220.98 0)
			(effects
				(font
					(size 1.27 1.27)
					(thickness 0.15)
				)
				(justify left bottom)
				(hide yes)
			)
		)
		(property "Datasheet" ""
			(at 139.7 226.06 0)
			(effects
				(font
					(size 1.27 1.27)
					(thickness 0.15)
				)
				(justify left bottom)
				(hide yes)
			)
		)
		(property "Description" ""
			(at 130.81 213.36 0)
			(effects
				(font
					(size 1.27 1.27)
				)
				(hide yes)
			)
		)
		(property "Author" "Antmicro"
			(at 139.7 220.98 0)
			(effects
				(font
					(size 1.27 1.27)
					(thickness 0.15)
				)
				(justify left bottom)
				(hide yes)
			)
		)
		(property "License" "Apache-2.0"
			(at 139.7 223.52 0)
			(effects
				(font
					(size 1.27 1.27)
					(thickness 0.15)
				)
				(justify left bottom)
				(hide yes)
			)
		)
		(pin "1"
		)
		(instances
			(project "polarfire-som"
				(path ""
					(reference "#PWR0236")
					(unit 1)
				)
			)
		)
	)
	(symbol
		(lib_id "antmicroCapacitors0402:C_10u_0402")
		(at 66.04 193.04 270)
		(mirror x)
		(unit 1)
		(exclude_from_sim no)
		(in_bom yes)
		(on_board yes)
		(dnp no)
		(property "Reference" "C250"
			(at 63.5 189.23 90)
			(effects
				(font
					(size 1.27 1.27)
					(thickness 0.15)
				)
				(justify right)
			)
		)
		(property "Value" "C_10u_0402"
			(at 55.88 172.72 0)
			(effects
				(font
					(size 1.27 1.27)
					(thickness 0.15)
				)
				(justify left bottom)
				(hide yes)
			)
		)
		(property "Footprint" "antmicro-footprints:C_0402_1005Metric"
			(at 53.34 172.72 0)
			(effects
				(font
					(size 1.27 1.27)
					(thickness 0.15)
				)
				(justify left bottom)
				(hide yes)
			)
		)
		(property "Datasheet" "https://www.yageo.com/en/Chart/Download/pdf/CC0402MRX5R5BB106"
			(at 50.8 172.72 0)
			(effects
				(font
					(size 1.27 1.27)
					(thickness 0.15)
				)
				(justify left bottom)
				(hide yes)
			)
		)
		(property "Description" "SMD Multilayer Ceramic Capacitor, 10 µF, 6.3 V, 0402 [1005 Metric], ± 20%, X5R, CC Series"
			(at 66.04 193.04 0)
			(effects
				(font
					(size 1.27 1.27)
				)
				(hide yes)
			)
		)
		(property "MPN" "CC0402MRX5R5BB106"
			(at 48.26 172.72 0)
			(effects
				(font
					(size 1.27 1.27)
					(thickness 0.15)
				)
				(justify left bottom)
				(hide yes)
			)
		)
		(property "Manufacturer" "YAGEO"
			(at 45.72 172.72 0)
			(effects
				(font
					(size 1.27 1.27)
					(thickness 0.15)
				)
				(justify left bottom)
				(hide yes)
			)
		)
		(property "License" "Apache-2.0"
			(at 43.18 172.72 0)
			(effects
				(font
					(size 1.27 1.27)
					(thickness 0.15)
				)
				(justify left bottom)
				(hide yes)
			)
		)
		(property "Author" "Antmicro"
			(at 40.64 172.72 0)
			(effects
				(font
					(size 1.27 1.27)
					(thickness 0.15)
				)
				(justify left bottom)
				(hide yes)
			)
		)
		(property "Val" "10u"
			(at 63.5 191.77 90)
			(effects
				(font
					(size 1.27 1.27)
					(thickness 0.15)
				)
				(justify right)
			)
		)
		(property "Voltage" ""
			(at 38.1 172.72 0)
			(effects
				(font
					(size 1.27 1.27)
				)
				(justify left bottom)
				(hide yes)
			)
		)
		(property "Dielectric" ""
			(at 35.56 172.72 0)
			(effects
				(font
					(size 1.27 1.27)
				)
				(justify left bottom)
				(hide yes)
			)
		)
		(property "Public" ""
			(at 33.02 172.72 0)
			(effects
				(font
					(size 1.27 1.27)
				)
				(justify left bottom)
				(hide yes)
			)
		)
		(pin "1"
		)
		(pin "2"
		)
		(instances
			(project "polarfire-som"
				(path ""
					(reference "C250")
					(unit 1)
				)
			)
		)
	)
	(symbol
		(lib_id "antmicroCapacitors0402:C_100n_0402")
		(at 166.37 81.28 0)
		(mirror y)
		(unit 1)
		(exclude_from_sim no)
		(in_bom yes)
		(on_board yes)
		(dnp no)
		(property "Reference" "C260"
			(at 162.56 80.01 0)
			(effects
				(font
					(size 1.27 1.27)
					(thickness 0.15)
				)
				(justify left)
			)
		)
		(property "Value" "C_100n_0402"
			(at 146.05 91.44 0)
			(effects
				(font
					(size 1.27 1.27)
					(thickness 0.15)
				)
				(justify left bottom)
				(hide yes)
			)
		)
		(property "Footprint" "antmicro-footprints:C_0402_1005Metric"
			(at 146.05 93.98 0)
			(effects
				(font
					(size 1.27 1.27)
					(thickness 0.15)
				)
				(justify left bottom)
				(hide yes)
			)
		)
		(property "Datasheet" "https://www.murata.com/products/productdetail?partno=GRM155R61H104KE14%23"
			(at 146.05 96.52 0)
			(effects
				(font
					(size 1.27 1.27)
					(thickness 0.15)
				)
				(justify left bottom)
				(hide yes)
			)
		)
		(property "Description" "SMD Multilayer Ceramic Capacitor, 0.1 µF, 50 V, 0402 [1005 Metric], ± 10%, X5R, GRM Series"
			(at 166.37 81.28 0)
			(effects
				(font
					(size 1.27 1.27)
				)
				(hide yes)
			)
		)
		(property "MPN" "GRM155R61H104KE14D"
			(at 146.05 99.06 0)
			(effects
				(font
					(size 1.27 1.27)
					(thickness 0.15)
				)
				(justify left bottom)
				(hide yes)
			)
		)
		(property "Manufacturer" "Murata"
			(at 146.05 101.6 0)
			(effects
				(font
					(size 1.27 1.27)
					(thickness 0.15)
				)
				(justify left bottom)
				(hide yes)
			)
		)
		(property "License" "Apache-2.0"
			(at 146.05 104.14 0)
			(effects
				(font
					(size 1.27 1.27)
					(thickness 0.15)
				)
				(justify left bottom)
				(hide yes)
			)
		)
		(property "Author" "Antmicro"
			(at 146.05 106.68 0)
			(effects
				(font
					(size 1.27 1.27)
					(thickness 0.15)
				)
				(justify left bottom)
				(hide yes)
			)
		)
		(property "Val" "100n"
			(at 172.72 80.645 0)
			(effects
				(font
					(size 1.27 1.27)
					(thickness 0.15)
				)
				(justify left bottom)
			)
		)
		(property "Voltage" "50V"
			(at 146.05 109.22 0)
			(effects
				(font
					(size 1.27 1.27)
				)
				(justify left bottom)
				(hide yes)
			)
		)
		(property "Dielectric" "X5R"
			(at 146.05 111.76 0)
			(effects
				(font
					(size 1.27 1.27)
				)
				(justify left bottom)
				(hide yes)
			)
		)
		(property "Public" ""
			(at 146.05 114.3 0)
			(effects
				(font
					(size 1.27 1.27)
				)
				(justify left bottom)
				(hide yes)
			)
		)
		(pin "1"
		)
		(pin "2"
		)
		(instances
			(project "polarfire-som"
				(path ""
					(reference "C260")
					(unit 1)
				)
			)
		)
	)
)
